FILE_TYPE = MACRO_DRAWING;
SET COLOR_WIRE YELLOW;
SET COLOR_PROP ORANGE;
SET COLOR_DOT WHITE;
SET COLOR_ARC YELLOW;
SET COLOR_BODY GREEN;
SET COLOR_NOTE PURPLE;
SET PROP_DISPLAY VALUE;
SET PAGE_NUMBER P39;
FORCEADD SOCKET4677_AZIF0045P001C01CS..31
(-1500 1675);
FORCEPROP 1 LAST PART_NUMBER DGA^7000023
J 0
(-2550 3925);
DISPLAY 0.723404 (-2550 3925);
PAINT GREEN (-2550 3925);
DISPLAY INVISIBLE (-2550 3925);
FORCEPROP 2 LAST PART_TYPE SMLF
J 0
(-2550 4100);
DISPLAY 1.021277 (-2550 4100);
FORCEPROP 1 LAST MATERIAL IO
J 0
(-2550 3850);
DISPLAY 0.723404 (-2550 3850);
PAINT GREEN (-2550 3850);
FORCEPROP 2 LAST VALUE SOCKET4677_AZIF0045-P001C01CS
J 0
(-2550 4050);
DISPLAY 1.021277 (-2550 4050);
FORCEPROP 1 LAST $LOCATION U2
J 0
(-2550 4000);
DISPLAY 0.723404 (-2550 4000);
PAINT GREEN (-2550 4000);
FORCEPROP 0 LASTPIN (-300 -250) $PN EH42
J 0
(-290 -240);
DISPLAY 0.680851 (-290 -240);
PAINT MONO (-290 -240);
FORCEPROP 0 LASTPIN (-300 -150) $PN EH55
J 0
(-290 -140);
DISPLAY 0.680851 (-290 -140);
PAINT MONO (-290 -140);
FORCEPROP 0 LASTPIN (-300 -100) $PN EH61
J 0
(-290 -90);
DISPLAY 0.680851 (-290 -90);
PAINT MONO (-290 -90);
FORCEPROP 0 LASTPIN (-300 -50) $PN EH67
J 0
(-290 -40);
DISPLAY 0.680851 (-290 -40);
PAINT MONO (-290 -40);
FORCEPROP 0 LASTPIN (-300 50) $PN EH79
J 0
(-290 60);
DISPLAY 0.680851 (-290 60);
PAINT MONO (-290 60);
FORCEPROP 0 LASTPIN (-300 300) $PN EJ11
J 0
(-290 310);
DISPLAY 0.680851 (-290 310);
PAINT MONO (-290 310);
FORCEPROP 0 LASTPIN (-300 400) $PN EJ17
J 0
(-290 410);
DISPLAY 0.680851 (-290 410);
PAINT MONO (-290 410);
FORCEPROP 0 LASTPIN (-300 550) $PN EJ25
J 0
(-290 560);
DISPLAY 0.680851 (-290 560);
PAINT MONO (-290 560);
FORCEPROP 0 LASTPIN (-300 700) $PN EJ35
J 0
(-290 710);
DISPLAY 0.680851 (-290 710);
PAINT MONO (-290 710);
FORCEPROP 0 LASTPIN (-300 1000) $PN EJ54
J 0
(-290 1010);
DISPLAY 0.680851 (-290 1010);
PAINT MONO (-290 1010);
FORCEPROP 0 LASTPIN (-300 1150) $PN EJ62
J 0
(-290 1160);
DISPLAY 0.680851 (-290 1160);
PAINT MONO (-290 1160);
FORCEPROP 0 LASTPIN (-300 1250) $PN EJ68
J 0
(-290 1260);
DISPLAY 0.680851 (-290 1260);
PAINT MONO (-290 1260);
FORCEPROP 0 LASTPIN (-300 1300) $PN EJ72
J 0
(-290 1310);
DISPLAY 0.680851 (-290 1310);
PAINT MONO (-290 1310);
FORCEPROP 0 LASTPIN (-300 1700) $PN EK16
J 0
(-290 1710);
DISPLAY 0.680851 (-290 1710);
PAINT MONO (-290 1710);
FORCEPROP 0 LASTPIN (-300 1750) $PN EK20
J 0
(-290 1760);
DISPLAY 0.680851 (-290 1760);
PAINT MONO (-290 1760);
FORCEPROP 0 LASTPIN (-300 1850) $PN EK26
J 0
(-290 1860);
DISPLAY 0.680851 (-290 1860);
PAINT MONO (-290 1860);
FORCEPROP 0 LASTPIN (-300 2150) $PN EK44
J 0
(-290 2160);
DISPLAY 0.680851 (-290 2160);
PAINT MONO (-290 2160);
FORCEPROP 0 LASTPIN (-300 2250) $PN EK51
J 0
(-290 2260);
DISPLAY 0.680851 (-290 2260);
PAINT MONO (-290 2260);
FORCEPROP 0 LASTPIN (-300 2300) $PN EK53
J 0
(-290 2310);
DISPLAY 0.680851 (-290 2310);
PAINT MONO (-290 2310);
FORCEPROP 0 LASTPIN (-300 2400) $PN EK59
J 0
(-290 2410);
DISPLAY 0.680851 (-290 2410);
PAINT MONO (-290 2410);
FORCEPROP 0 LASTPIN (-300 2450) $PN EK63
J 0
(-290 2460);
DISPLAY 0.680851 (-290 2460);
PAINT MONO (-290 2460);
FORCEPROP 0 LASTPIN (-300 2600) $PN EK71
J 0
(-290 2610);
DISPLAY 0.680851 (-290 2610);
PAINT MONO (-290 2610);
FORCEPROP 0 LASTPIN (-300 2700) $PN EK77
J 0
(-290 2710);
DISPLAY 0.680851 (-290 2710);
PAINT MONO (-290 2710);
FORCEPROP 0 LASTPIN (-300 2750) $PN EK79
J 0
(-290 2760);
DISPLAY 0.680851 (-290 2760);
PAINT MONO (-290 2760);
FORCEPROP 0 LASTPIN (-300 2800) $PN EK83
J 0
(-290 2810);
DISPLAY 0.680851 (-290 2810);
PAINT MONO (-290 2810);
FORCEPROP 0 LASTPIN (-300 2850) $PN EK89
J 0
(-290 2860);
DISPLAY 0.680851 (-290 2860);
PAINT MONO (-290 2860);
FORCEPROP 0 LASTPIN (-300 3100) $PN EL15
J 0
(-290 3110);
DISPLAY 0.680851 (-290 3110);
PAINT MONO (-290 3110);
FORCEPROP 0 LASTPIN (-300 3400) $PN EL52
J 0
(-290 3410);
DISPLAY 0.680851 (-290 3410);
PAINT MONO (-290 3410);
FORCEPROP 0 LASTPIN (-300 3450) $PN EL58
J 0
(-290 3460);
DISPLAY 0.680851 (-290 3460);
PAINT MONO (-290 3460);
FORCEPROP 0 LASTPIN (-300 3000) $PN EL7
J 0
(-290 3010);
DISPLAY 0.680851 (-290 3010);
PAINT MONO (-290 3010);
FORCEPROP 0 LASTPIN (-300 3550) $PN EL70
J 0
(-290 3560);
DISPLAY 0.680851 (-290 3560);
PAINT MONO (-290 3560);
FORCEPROP 0 LASTPIN (-300 3600) $PN EL72
J 0
(-290 3610);
DISPLAY 0.680851 (-290 3610);
PAINT MONO (-290 3610);
FORCEPROP 0 LASTPIN (-2700 -300) $PN EL86
J 2
(-2710 -290);
DISPLAY 0.680851 (-2710 -290);
PAINT MONO (-2710 -290);
FORCEPROP 0 LASTPIN (-300 3050) $PN EL9
J 0
(-290 3060);
DISPLAY 0.680851 (-290 3060);
PAINT MONO (-290 3060);
FORCEPROP 0 LASTPIN (-2700 -150) $PN EM49
J 2
(-2710 -140);
DISPLAY 0.680851 (-2710 -140);
PAINT MONO (-2710 -140);
FORCEPROP 0 LASTPIN (-2700 -50) $PN EM79
J 2
(-2710 -40);
DISPLAY 0.680851 (-2710 -40);
PAINT MONO (-2710 -40);
FORCEPROP 0 LASTPIN (-300 -300) $PN EH36
J 0
(-290 -290);
DISPLAY 0.680851 (-290 -290);
PAINT MONO (-290 -290);
FORCEPROP 0 LASTPIN (-300 -200) $PN EH49
J 0
(-290 -190);
DISPLAY 0.680851 (-290 -190);
PAINT MONO (-290 -190);
FORCEPROP 0 LASTPIN (-300 0) $PN EH73
J 0
(-290 10);
DISPLAY 0.680851 (-290 10);
PAINT MONO (-290 10);
FORCEPROP 0 LASTPIN (-300 100) $PN EH81
J 0
(-290 110);
DISPLAY 0.680851 (-290 110);
PAINT MONO (-290 110);
FORCEPROP 0 LASTPIN (-300 150) $PN EH83
J 0
(-290 160);
DISPLAY 0.680851 (-290 160);
PAINT MONO (-290 160);
FORCEPROP 0 LASTPIN (-300 350) $PN EJ13
J 0
(-290 360);
DISPLAY 0.680851 (-290 360);
PAINT MONO (-290 360);
FORCEPROP 0 LASTPIN (-300 450) $PN EJ19
J 0
(-290 460);
DISPLAY 0.680851 (-290 460);
PAINT MONO (-290 460);
FORCEPROP 0 LASTPIN (-2700 850) $PN EN39
J 2
(-2710 860);
DISPLAY 0.680851 (-2710 860);
PAINT MONO (-2710 860);
FORCEPROP 0 LASTPIN (-300 500) $PN EJ23
J 0
(-290 510);
DISPLAY 0.680851 (-290 510);
PAINT MONO (-290 510);
FORCEPROP 0 LASTPIN (-300 600) $PN EJ29
J 0
(-290 610);
DISPLAY 0.680851 (-290 610);
PAINT MONO (-290 610);
FORCEPROP 0 LASTPIN (-300 650) $PN EJ31
J 0
(-290 660);
DISPLAY 0.680851 (-290 660);
PAINT MONO (-290 660);
FORCEPROP 0 LASTPIN (-300 750) $PN EJ37
J 0
(-290 760);
DISPLAY 0.680851 (-290 760);
PAINT MONO (-290 760);
FORCEPROP 0 LASTPIN (-300 800) $PN EJ41
J 0
(-290 810);
DISPLAY 0.680851 (-290 810);
PAINT MONO (-290 810);
FORCEPROP 0 LASTPIN (-300 850) $PN EJ43
J 0
(-290 860);
DISPLAY 0.680851 (-290 860);
PAINT MONO (-290 860);
FORCEPROP 0 LASTPIN (-300 900) $PN EJ48
J 0
(-290 910);
DISPLAY 0.680851 (-290 910);
PAINT MONO (-290 910);
FORCEPROP 0 LASTPIN (-300 950) $PN EJ50
J 0
(-290 960);
DISPLAY 0.680851 (-290 960);
PAINT MONO (-290 960);
FORCEPROP 0 LASTPIN (-2700 1300) $PN EN58
J 2
(-2710 1310);
DISPLAY 0.680851 (-2710 1310);
PAINT MONO (-2710 1310);
FORCEPROP 0 LASTPIN (-2700 1350) $PN EN60
J 2
(-2710 1360);
DISPLAY 0.680851 (-2710 1360);
PAINT MONO (-2710 1360);
FORCEPROP 0 LASTPIN (-2700 1400) $PN EN62
J 2
(-2710 1410);
DISPLAY 0.680851 (-2710 1410);
PAINT MONO (-2710 1410);
FORCEPROP 0 LASTPIN (-300 1050) $PN EJ56
J 0
(-290 1060);
DISPLAY 0.680851 (-290 1060);
PAINT MONO (-290 1060);
FORCEPROP 0 LASTPIN (-2700 1500) $PN EN66
J 2
(-2710 1510);
DISPLAY 0.680851 (-2710 1510);
PAINT MONO (-2710 1510);
FORCEPROP 0 LASTPIN (-2700 1550) $PN EN72
J 2
(-2710 1560);
DISPLAY 0.680851 (-2710 1560);
PAINT MONO (-2710 1560);
FORCEPROP 0 LASTPIN (-300 1100) $PN EJ60
J 0
(-290 1110);
DISPLAY 0.680851 (-290 1110);
PAINT MONO (-290 1110);
FORCEPROP 0 LASTPIN (-300 1200) $PN EJ66
J 0
(-290 1210);
DISPLAY 0.680851 (-290 1210);
PAINT MONO (-290 1210);
FORCEPROP 0 LASTPIN (-300 200) $PN EJ7
J 0
(-290 210);
DISPLAY 0.680851 (-290 210);
PAINT MONO (-290 210);
FORCEPROP 0 LASTPIN (-2700 1700) $PN EN88
J 2
(-2710 1710);
DISPLAY 0.680851 (-2710 1710);
PAINT MONO (-2710 1710);
FORCEPROP 0 LASTPIN (-2700 100) $PN EN9
J 2
(-2710 110);
DISPLAY 0.680851 (-2710 110);
PAINT MONO (-2710 110);
FORCEPROP 0 LASTPIN (-300 1350) $PN EJ74
J 0
(-290 1360);
DISPLAY 0.680851 (-290 1360);
PAINT MONO (-290 1360);
FORCEPROP 0 LASTPIN (-300 1400) $PN EJ78
J 0
(-290 1410);
DISPLAY 0.680851 (-290 1410);
PAINT MONO (-290 1410);
FORCEPROP 0 LASTPIN (-300 1450) $PN EJ88
J 0
(-290 1460);
DISPLAY 0.680851 (-290 1460);
PAINT MONO (-290 1460);
FORCEPROP 0 LASTPIN (-300 250) $PN EJ9
J 0
(-290 260);
DISPLAY 0.680851 (-290 260);
PAINT MONO (-290 260);
FORCEPROP 0 LASTPIN (-300 1600) $PN EK10
J 0
(-290 1610);
DISPLAY 0.680851 (-290 1610);
PAINT MONO (-290 1610);
FORCEPROP 0 LASTPIN (-2700 1800) $PN EP69
J 2
(-2710 1810);
DISPLAY 0.680851 (-2710 1810);
PAINT MONO (-2710 1810);
FORCEPROP 0 LASTPIN (-2700 1850) $PN EP71
J 2
(-2710 1860);
DISPLAY 0.680851 (-2710 1860);
PAINT MONO (-2710 1860);
FORCEPROP 0 LASTPIN (-2700 1900) $PN EP77
J 2
(-2710 1910);
DISPLAY 0.680851 (-2710 1910);
PAINT MONO (-2710 1910);
FORCEPROP 0 LASTPIN (-300 1650) $PN EK14
J 0
(-290 1660);
DISPLAY 0.680851 (-290 1660);
PAINT MONO (-290 1660);
FORCEPROP 0 LASTPIN (-2700 2150) $PN ER15
J 2
(-2710 2160);
DISPLAY 0.680851 (-2710 2160);
PAINT MONO (-2710 2160);
FORCEPROP 0 LASTPIN (-2700 2200) $PN ER21
J 2
(-2710 2210);
DISPLAY 0.680851 (-2710 2210);
PAINT MONO (-2710 2210);
FORCEPROP 0 LASTPIN (-300 1500) $PN EK2
J 0
(-290 1510);
DISPLAY 0.680851 (-290 1510);
PAINT MONO (-290 1510);
FORCEPROP 0 LASTPIN (-300 1800) $PN EK22
J 0
(-290 1810);
DISPLAY 0.680851 (-290 1810);
PAINT MONO (-290 1810);
FORCEPROP 0 LASTPIN (-300 1900) $PN EK28
J 0
(-290 1910);
DISPLAY 0.680851 (-290 1910);
PAINT MONO (-290 1910);
FORCEPROP 0 LASTPIN (-300 1950) $PN EK32
J 0
(-290 1960);
DISPLAY 0.680851 (-290 1960);
PAINT MONO (-290 1960);
FORCEPROP 0 LASTPIN (-2700 2350) $PN ER39
J 2
(-2710 2360);
DISPLAY 0.680851 (-2710 2360);
PAINT MONO (-2710 2360);
FORCEPROP 0 LASTPIN (-300 2000) $PN EK34
J 0
(-290 2010);
DISPLAY 0.680851 (-290 2010);
PAINT MONO (-290 2010);
FORCEPROP 0 LASTPIN (-2700 2400) $PN ER52
J 2
(-2710 2410);
DISPLAY 0.680851 (-2710 2410);
PAINT MONO (-2710 2410);
FORCEPROP 0 LASTPIN (-300 2050) $PN EK38
J 0
(-290 2060);
DISPLAY 0.680851 (-290 2060);
PAINT MONO (-290 2060);
FORCEPROP 0 LASTPIN (-300 1550) $PN EK4
J 0
(-290 1560);
DISPLAY 0.680851 (-290 1560);
PAINT MONO (-290 1560);
FORCEPROP 0 LASTPIN (-2700 2450) $PN ER58
J 2
(-2710 2460);
DISPLAY 0.680851 (-2710 2460);
PAINT MONO (-2710 2460);
FORCEPROP 0 LASTPIN (-2700 2500) $PN ER64
J 2
(-2710 2510);
DISPLAY 0.680851 (-2710 2510);
PAINT MONO (-2710 2510);
FORCEPROP 0 LASTPIN (-300 2100) $PN EK40
J 0
(-290 2110);
DISPLAY 0.680851 (-290 2110);
PAINT MONO (-290 2110);
FORCEPROP 0 LASTPIN (-300 2200) $PN EK47
J 0
(-290 2210);
DISPLAY 0.680851 (-290 2210);
PAINT MONO (-290 2210);
FORCEPROP 0 LASTPIN (-300 2350) $PN EK57
J 0
(-290 2360);
DISPLAY 0.680851 (-290 2360);
PAINT MONO (-290 2360);
FORCEPROP 0 LASTPIN (-300 2500) $PN EK65
J 0
(-290 2510);
DISPLAY 0.680851 (-290 2510);
PAINT MONO (-290 2510);
FORCEPROP 0 LASTPIN (-300 2550) $PN EK69
J 0
(-290 2560);
DISPLAY 0.680851 (-290 2560);
PAINT MONO (-290 2560);
FORCEPROP 0 LASTPIN (-300 2650) $PN EK75
J 0
(-290 2660);
DISPLAY 0.680851 (-290 2660);
PAINT MONO (-290 2660);
FORCEPROP 0 LASTPIN (-300 3150) $PN EL21
J 0
(-290 3160);
DISPLAY 0.680851 (-290 3160);
PAINT MONO (-290 3160);
FORCEPROP 0 LASTPIN (-2700 2100) $PN ER9
J 2
(-2710 2110);
DISPLAY 0.680851 (-2710 2110);
PAINT MONO (-2710 2110);
FORCEPROP 0 LASTPIN (-300 3200) $PN EL27
J 0
(-290 3210);
DISPLAY 0.680851 (-290 3210);
PAINT MONO (-290 3210);
FORCEPROP 0 LASTPIN (-2700 2900) $PN ET14
J 2
(-2710 2910);
DISPLAY 0.680851 (-2710 2910);
PAINT MONO (-2710 2910);
FORCEPROP 0 LASTPIN (-300 2900) $PN EL3
J 0
(-290 2910);
DISPLAY 0.680851 (-290 2910);
PAINT MONO (-290 2910);
FORCEPROP 0 LASTPIN (-2700 3000) $PN ET20
J 2
(-2710 3010);
DISPLAY 0.680851 (-2710 3010);
PAINT MONO (-2710 3010);
FORCEPROP 0 LASTPIN (-300 3250) $PN EL33
J 0
(-290 3260);
DISPLAY 0.680851 (-290 3260);
PAINT MONO (-290 3260);
FORCEPROP 0 LASTPIN (-2700 3100) $PN ET26
J 2
(-2710 3110);
DISPLAY 0.680851 (-2710 3110);
PAINT MONO (-2710 3110);
FORCEPROP 0 LASTPIN (-300 3300) $PN EL39
J 0
(-290 3310);
DISPLAY 0.680851 (-290 3310);
PAINT MONO (-290 3310);
FORCEPROP 0 LASTPIN (-2700 3200) $PN ET32
J 2
(-2710 3210);
DISPLAY 0.680851 (-2710 3210);
PAINT MONO (-2710 3210);
FORCEPROP 0 LASTPIN (-300 3350) $PN EL45
J 0
(-290 3360);
DISPLAY 0.680851 (-290 3360);
PAINT MONO (-290 3360);
FORCEPROP 0 LASTPIN (-300 2950) $PN EL5
J 0
(-290 2960);
DISPLAY 0.680851 (-290 2960);
PAINT MONO (-290 2960);
FORCEPROP 0 LASTPIN (-300 3500) $PN EL64
J 0
(-290 3510);
DISPLAY 0.680851 (-290 3510);
PAINT MONO (-290 3510);
FORCEPROP 0 LASTPIN (-300 3650) $PN EL76
J 0
(-290 3660);
DISPLAY 0.680851 (-290 3660);
PAINT MONO (-290 3660);
FORCEPROP 0 LASTPIN (-2700 3550) $PN ET53
J 2
(-2710 3560);
DISPLAY 0.680851 (-2710 3560);
PAINT MONO (-2710 3560);
FORCEPROP 0 LASTPIN (-2700 -200) $PN EM42
J 2
(-2710 -190);
DISPLAY 0.680851 (-2710 -190);
PAINT MONO (-2710 -190);
FORCEPROP 0 LASTPIN (-2700 3650) $PN ET59
J 2
(-2710 3660);
DISPLAY 0.680851 (-2710 3660);
PAINT MONO (-2710 3660);
FORCEPROP 0 LASTPIN (-2700 -100) $PN EM73
J 2
(-2710 -90);
DISPLAY 0.680851 (-2710 -90);
PAINT MONO (-2710 -90);
FORCEPROP 0 LASTPIN (-2700 -250) $PN EM8
J 2
(-2710 -240);
DISPLAY 0.680851 (-2710 -240);
PAINT MONO (-2710 -240);
FORCEPROP 0 LASTPIN (-2700 0) $PN EM81
J 2
(-2710 10);
DISPLAY 0.680851 (-2710 10);
PAINT MONO (-2710 10);
FORCEPROP 0 LASTPIN (-2700 50) $PN EM83
J 2
(-2710 60);
DISPLAY 0.680851 (-2710 60);
PAINT MONO (-2710 60);
FORCEPROP 0 LASTPIN (-2700 150) $PN EN11
J 2
(-2710 160);
DISPLAY 0.680851 (-2710 160);
PAINT MONO (-2710 160);
FORCEPROP 0 LASTPIN (-2700 200) $PN EN13
J 2
(-2710 210);
DISPLAY 0.680851 (-2710 210);
PAINT MONO (-2710 210);
FORCEPROP 0 LASTPIN (-2700 250) $PN EN15
J 2
(-2710 260);
DISPLAY 0.680851 (-2710 260);
PAINT MONO (-2710 260);
FORCEPROP 0 LASTPIN (-2700 300) $PN EN17
J 2
(-2710 310);
DISPLAY 0.680851 (-2710 310);
PAINT MONO (-2710 310);
FORCEPROP 0 LASTPIN (-2700 350) $PN EN19
J 2
(-2710 360);
DISPLAY 0.680851 (-2710 360);
PAINT MONO (-2710 360);
FORCEPROP 0 LASTPIN (-2700 400) $PN EN21
J 2
(-2710 410);
DISPLAY 0.680851 (-2710 410);
PAINT MONO (-2710 410);
FORCEPROP 0 LASTPIN (-2700 450) $PN EN23
J 2
(-2710 460);
DISPLAY 0.680851 (-2710 460);
PAINT MONO (-2710 460);
FORCEPROP 0 LASTPIN (-2700 500) $PN EN25
J 2
(-2710 510);
DISPLAY 0.680851 (-2710 510);
PAINT MONO (-2710 510);
FORCEPROP 0 LASTPIN (-2700 550) $PN EN27
J 2
(-2710 560);
DISPLAY 0.680851 (-2710 560);
PAINT MONO (-2710 560);
FORCEPROP 0 LASTPIN (-2700 600) $PN EN29
J 2
(-2710 610);
DISPLAY 0.680851 (-2710 610);
PAINT MONO (-2710 610);
FORCEPROP 0 LASTPIN (-2700 650) $PN EN31
J 2
(-2710 660);
DISPLAY 0.680851 (-2710 660);
PAINT MONO (-2710 660);
FORCEPROP 0 LASTPIN (-2700 700) $PN EN33
J 2
(-2710 710);
DISPLAY 0.680851 (-2710 710);
PAINT MONO (-2710 710);
FORCEPROP 0 LASTPIN (-2700 750) $PN EN35
J 2
(-2710 760);
DISPLAY 0.680851 (-2710 760);
PAINT MONO (-2710 760);
FORCEPROP 0 LASTPIN (-2700 800) $PN EN37
J 2
(-2710 810);
DISPLAY 0.680851 (-2710 810);
PAINT MONO (-2710 810);
FORCEPROP 0 LASTPIN (-2700 900) $PN EN41
J 2
(-2710 910);
DISPLAY 0.680851 (-2710 910);
PAINT MONO (-2710 910);
FORCEPROP 0 LASTPIN (-2700 950) $PN EN43
J 2
(-2710 960);
DISPLAY 0.680851 (-2710 960);
PAINT MONO (-2710 960);
FORCEPROP 0 LASTPIN (-2700 1000) $PN EN45
J 2
(-2710 1010);
DISPLAY 0.680851 (-2710 1010);
PAINT MONO (-2710 1010);
FORCEPROP 0 LASTPIN (-2700 1050) $PN EN48
J 2
(-2710 1060);
DISPLAY 0.680851 (-2710 1060);
PAINT MONO (-2710 1060);
FORCEPROP 0 LASTPIN (-2700 1100) $PN EN50
J 2
(-2710 1110);
DISPLAY 0.680851 (-2710 1110);
PAINT MONO (-2710 1110);
FORCEPROP 0 LASTPIN (-2700 1150) $PN EN52
J 2
(-2710 1160);
DISPLAY 0.680851 (-2710 1160);
PAINT MONO (-2710 1160);
FORCEPROP 0 LASTPIN (-2700 1200) $PN EN54
J 2
(-2710 1210);
DISPLAY 0.680851 (-2710 1210);
PAINT MONO (-2710 1210);
FORCEPROP 0 LASTPIN (-2700 1250) $PN EN56
J 2
(-2710 1260);
DISPLAY 0.680851 (-2710 1260);
PAINT MONO (-2710 1260);
FORCEPROP 0 LASTPIN (-2700 1450) $PN EN64
J 2
(-2710 1460);
DISPLAY 0.680851 (-2710 1460);
PAINT MONO (-2710 1460);
FORCEPROP 0 LASTPIN (-2700 1600) $PN EN78
J 2
(-2710 1610);
DISPLAY 0.680851 (-2710 1610);
PAINT MONO (-2710 1610);
FORCEPROP 0 LASTPIN (-2700 1650) $PN EN80
J 2
(-2710 1660);
DISPLAY 0.680851 (-2710 1660);
PAINT MONO (-2710 1660);
FORCEPROP 0 LASTPIN (-2700 1750) $PN EP67
J 2
(-2710 1760);
DISPLAY 0.680851 (-2710 1760);
PAINT MONO (-2710 1760);
FORCEPROP 0 LASTPIN (-2700 1950) $PN EP83
J 2
(-2710 1960);
DISPLAY 0.680851 (-2710 1960);
PAINT MONO (-2710 1960);
FORCEPROP 0 LASTPIN (-2700 2250) $PN ER27
J 2
(-2710 2260);
DISPLAY 0.680851 (-2710 2260);
PAINT MONO (-2710 2260);
FORCEPROP 0 LASTPIN (-2700 2300) $PN ER33
J 2
(-2710 2310);
DISPLAY 0.680851 (-2710 2310);
PAINT MONO (-2710 2310);
FORCEPROP 0 LASTPIN (-2700 2000) $PN ER5
J 2
(-2710 2010);
DISPLAY 0.680851 (-2710 2010);
PAINT MONO (-2710 2010);
FORCEPROP 0 LASTPIN (-2700 2050) $PN ER7
J 2
(-2710 2060);
DISPLAY 0.680851 (-2710 2060);
PAINT MONO (-2710 2060);
FORCEPROP 0 LASTPIN (-2700 2550) $PN ER70
J 2
(-2710 2560);
DISPLAY 0.680851 (-2710 2560);
PAINT MONO (-2710 2560);
FORCEPROP 0 LASTPIN (-2700 2600) $PN ER74
J 2
(-2710 2610);
DISPLAY 0.680851 (-2710 2610);
PAINT MONO (-2710 2610);
FORCEPROP 0 LASTPIN (-2700 2650) $PN ER78
J 2
(-2710 2660);
DISPLAY 0.680851 (-2710 2660);
PAINT MONO (-2710 2660);
FORCEPROP 0 LASTPIN (-2700 2700) $PN ER80
J 2
(-2710 2710);
DISPLAY 0.680851 (-2710 2710);
PAINT MONO (-2710 2710);
FORCEPROP 0 LASTPIN (-2700 2750) $PN ER84
J 2
(-2710 2760);
DISPLAY 0.680851 (-2710 2760);
PAINT MONO (-2710 2760);
FORCEPROP 0 LASTPIN (-2700 2800) $PN ER86
J 2
(-2710 2810);
DISPLAY 0.680851 (-2710 2810);
PAINT MONO (-2710 2810);
FORCEPROP 0 LASTPIN (-2700 2850) $PN ET10
J 2
(-2710 2860);
DISPLAY 0.680851 (-2710 2860);
PAINT MONO (-2710 2860);
FORCEPROP 0 LASTPIN (-2700 2950) $PN ET16
J 2
(-2710 2960);
DISPLAY 0.680851 (-2710 2960);
PAINT MONO (-2710 2960);
FORCEPROP 0 LASTPIN (-2700 3050) $PN ET22
J 2
(-2710 3060);
DISPLAY 0.680851 (-2710 3060);
PAINT MONO (-2710 3060);
FORCEPROP 0 LASTPIN (-2700 3150) $PN ET28
J 2
(-2710 3160);
DISPLAY 0.680851 (-2710 3160);
PAINT MONO (-2710 3160);
FORCEPROP 0 LASTPIN (-2700 3250) $PN ET34
J 2
(-2710 3260);
DISPLAY 0.680851 (-2710 3260);
PAINT MONO (-2710 3260);
FORCEPROP 0 LASTPIN (-2700 3300) $PN ET38
J 2
(-2710 3310);
DISPLAY 0.680851 (-2710 3310);
PAINT MONO (-2710 3310);
FORCEPROP 0 LASTPIN (-2700 3600) $PN ET57
J 2
(-2710 3610);
DISPLAY 0.680851 (-2710 3610);
PAINT MONO (-2710 3610);
FORCEPROP 0 LASTPIN (-2700 3350) $PN ER41
J 2
(-2710 3360);
DISPLAY 0.680851 (-2710 3360);
PAINT MONO (-2710 3360);
FORCEPROP 0 LASTPIN (-2700 3400) $PN ER43
J 2
(-2710 3410);
DISPLAY 0.680851 (-2710 3410);
PAINT MONO (-2710 3410);
FORCEPROP 0 LASTPIN (-2700 3450) $PN ER48
J 2
(-2710 3460);
DISPLAY 0.680851 (-2710 3460);
PAINT MONO (-2710 3460);
FORCEPROP 0 LASTPIN (-2700 3500) $PN ER50
J 2
(-2710 3510);
DISPLAY 0.680851 (-2710 3510);
PAINT MONO (-2710 3510);
FORCEPROP 2 LAST CDS_LIB pure_quanta
J 0
(-1500 1675);
DISPLAY INVISIBLE (-1500 1675);
FORCEPROP 1 LAST NEEDS_NO_SIZE TRUE
J 0
(-1500 1675);
DISPLAY 0.723404 (-1500 1675);
PAINT GREEN (-1500 1675);
DISPLAY INVISIBLE (-1500 1675);
FORCEPROP 1 LAST CDS_LMAN_SYM_OUTLINE -1050,2150,1050,-2100
J 0
(-1500 1675);
DISPLAY 0.468085 (-1500 1675);
PAINT GREEN (-1500 1675);
DISPLAY INVISIBLE (-1500 1675);
FORCEPROP 2 LAST CDS_LOCATION U2
J 0
(-2550 4150);
DISPLAY 1.021277 (-2550 4150);
DISPLAY INVISIBLE (-2550 4150);
FORCEPROP 0 LAST $SEC 31
J 0
(-2550 4150);
DISPLAY 0.680851 (-2550 4150);
PAINT MONO (-2550 4150);
DISPLAY INVISIBLE (-2550 4150);
FORCEPROP 2 LAST CDS_SEC 31
J 0
(-2550 4150);
DISPLAY 1.021277 (-2550 4150);
DISPLAY INVISIBLE (-2550 4150);
FORCEPROP 1 LAST PATH I1
J 0
(-1500 1675);
DISPLAY 0.723404 (-1500 1675);
PAINT GREEN (-1500 1675);
DISPLAY INVISIBLE (-1500 1675);
FORCEADD SOCKET4677_AZIF0045P001C01CS..33
(4575 1675);
FORCEPROP 1 LAST PART_NUMBER DGA^7000023
J 0
(3525 3925);
DISPLAY 0.723404 (3525 3925);
PAINT GREEN (3525 3925);
DISPLAY INVISIBLE (3525 3925);
FORCEPROP 2 LAST PART_TYPE SMLF
J 0
(3525 4100);
DISPLAY 1.021277 (3525 4100);
FORCEPROP 1 LAST MATERIAL IO
J 0
(3525 3850);
DISPLAY 0.723404 (3525 3850);
PAINT GREEN (3525 3850);
FORCEPROP 2 LAST VALUE SOCKET4677_AZIF0045-P001C01CS
J 0
(3525 4050);
DISPLAY 1.021277 (3525 4050);
FORCEPROP 1 LAST $LOCATION U2
J 0
(3525 4000);
DISPLAY 0.723404 (3525 4000);
PAINT GREEN (3525 4000);
FORCEPROP 0 LASTPIN (5775 700) $PN DM51
J 0
(5785 710);
DISPLAY 0.680851 (5785 710);
PAINT MONO (5785 710);
FORCEPROP 0 LASTPIN (5775 1250) $PN DM73
J 0
(5785 1260);
DISPLAY 0.680851 (5785 1260);
PAINT MONO (5785 1260);
FORCEPROP 0 LASTPIN (5775 1450) $PN DN17
J 0
(5785 1460);
DISPLAY 0.680851 (5785 1460);
PAINT MONO (5785 1460);
FORCEPROP 0 LASTPIN (5775 1500) $PN DN39
J 0
(5785 1510);
DISPLAY 0.680851 (5785 1510);
PAINT MONO (5785 1510);
FORCEPROP 0 LASTPIN (5775 1550) $PN DN52
J 0
(5785 1560);
DISPLAY 0.680851 (5785 1560);
PAINT MONO (5785 1560);
FORCEPROP 0 LASTPIN (5775 1850) $PN DP12
J 0
(5785 1860);
DISPLAY 0.680851 (5785 1860);
PAINT MONO (5785 1860);
FORCEPROP 0 LASTPIN (5775 1950) $PN DP18
J 0
(5785 1960);
DISPLAY 0.680851 (5785 1960);
PAINT MONO (5785 1960);
FORCEPROP 0 LASTPIN (5775 2000) $PN DP24
J 0
(5785 2010);
DISPLAY 0.680851 (5785 2010);
PAINT MONO (5785 2010);
FORCEPROP 0 LASTPIN (5775 2150) $PN DP42
J 0
(5785 2160);
DISPLAY 0.680851 (5785 2160);
PAINT MONO (5785 2160);
FORCEPROP 0 LASTPIN (5775 2250) $PN DP55
J 0
(5785 2260);
DISPLAY 0.680851 (5785 2260);
PAINT MONO (5785 2260);
FORCEPROP 0 LASTPIN (5775 2300) $PN DP61
J 0
(5785 2310);
DISPLAY 0.680851 (5785 2310);
PAINT MONO (5785 2310);
FORCEPROP 0 LASTPIN (5775 2350) $PN DP67
J 0
(5785 2360);
DISPLAY 0.680851 (5785 2360);
PAINT MONO (5785 2360);
FORCEPROP 0 LASTPIN (5775 2550) $PN DP91
J 0
(5785 2560);
DISPLAY 0.680851 (5785 2560);
PAINT MONO (5785 2560);
FORCEPROP 0 LASTPIN (5775 2900) $PN DR25
J 0
(5785 2910);
DISPLAY 0.680851 (5785 2910);
PAINT MONO (5785 2910);
FORCEPROP 0 LASTPIN (5775 3050) $PN DR35
J 0
(5785 3060);
DISPLAY 0.680851 (5785 3060);
PAINT MONO (5785 3060);
FORCEPROP 0 LASTPIN (5775 2650) $PN DR5
J 0
(5785 2660);
DISPLAY 0.680851 (5785 2660);
PAINT MONO (5785 2660);
FORCEPROP 0 LASTPIN (5775 3350) $PN DR54
J 0
(5785 3360);
DISPLAY 0.680851 (5785 3360);
PAINT MONO (5785 3360);
FORCEPROP 0 LASTPIN (5775 3450) $PN DR60
J 0
(5785 3460);
DISPLAY 0.680851 (5785 3460);
PAINT MONO (5785 3460);
FORCEPROP 0 LASTPIN (5775 3500) $PN DR62
J 0
(5785 3510);
DISPLAY 0.680851 (5785 3510);
PAINT MONO (5785 3510);
FORCEPROP 0 LASTPIN (5775 3600) $PN DR68
J 0
(5785 3610);
DISPLAY 0.680851 (5785 3610);
PAINT MONO (5785 3610);
FORCEPROP 0 LASTPIN (5775 3650) $PN DR72
J 0
(5785 3660);
DISPLAY 0.680851 (5785 3660);
PAINT MONO (5785 3660);
FORCEPROP 0 LASTPIN (3375 50) $PN DT16
J 2
(3365 60);
DISPLAY 0.680851 (3365 60);
PAINT MONO (3365 60);
FORCEPROP 0 LASTPIN (3375 100) $PN DT20
J 2
(3365 110);
DISPLAY 0.680851 (3365 110);
PAINT MONO (3365 110);
FORCEPROP 0 LASTPIN (3375 200) $PN DT26
J 2
(3365 210);
DISPLAY 0.680851 (3365 210);
PAINT MONO (3365 210);
FORCEPROP 0 LASTPIN (3375 -100) $PN DT4
J 2
(3365 -90);
DISPLAY 0.680851 (3365 -90);
PAINT MONO (3365 -90);
FORCEPROP 0 LASTPIN (3375 500) $PN DT44
J 2
(3365 510);
DISPLAY 0.680851 (3365 510);
PAINT MONO (3365 510);
FORCEPROP 0 LASTPIN (3375 600) $PN DT51
J 2
(3365 610);
DISPLAY 0.680851 (3365 610);
PAINT MONO (3365 610);
FORCEPROP 0 LASTPIN (3375 650) $PN DT53
J 2
(3365 660);
DISPLAY 0.680851 (3365 660);
PAINT MONO (3365 660);
FORCEPROP 0 LASTPIN (3375 750) $PN DT59
J 2
(3365 760);
DISPLAY 0.680851 (3365 760);
PAINT MONO (3365 760);
FORCEPROP 0 LASTPIN (3375 800) $PN DT63
J 2
(3365 810);
DISPLAY 0.680851 (3365 810);
PAINT MONO (3365 810);
FORCEPROP 0 LASTPIN (3375 1050) $PN DT83
J 2
(3365 1060);
DISPLAY 0.680851 (3365 1060);
PAINT MONO (3365 1060);
FORCEPROP 0 LASTPIN (3375 1250) $PN DU39
J 2
(3365 1260);
DISPLAY 0.680851 (3365 1260);
PAINT MONO (3365 1260);
FORCEPROP 0 LASTPIN (3375 1300) $PN DU45
J 2
(3365 1310);
DISPLAY 0.680851 (3365 1310);
PAINT MONO (3365 1310);
FORCEPROP 0 LASTPIN (3375 1350) $PN DU52
J 2
(3365 1360);
DISPLAY 0.680851 (3365 1360);
PAINT MONO (3365 1360);
FORCEPROP 0 LASTPIN (3375 1400) $PN DU58
J 2
(3365 1410);
DISPLAY 0.680851 (3365 1410);
PAINT MONO (3365 1410);
FORCEPROP 0 LASTPIN (3375 1450) $PN DU64
J 2
(3365 1460);
DISPLAY 0.680851 (3365 1460);
PAINT MONO (3365 1460);
FORCEPROP 0 LASTPIN (3375 1500) $PN DU70
J 2
(3365 1510);
DISPLAY 0.680851 (3365 1510);
PAINT MONO (3365 1510);
FORCEPROP 0 LASTPIN (3375 1850) $PN DV12
J 2
(3365 1860);
DISPLAY 0.680851 (3365 1860);
PAINT MONO (3365 1860);
FORCEPROP 0 LASTPIN (3375 1900) $PN DV16
J 2
(3365 1910);
DISPLAY 0.680851 (3365 1910);
PAINT MONO (3365 1910);
FORCEPROP 0 LASTPIN (3375 1750) $PN DV4
J 2
(3365 1760);
DISPLAY 0.680851 (3365 1760);
PAINT MONO (3365 1760);
FORCEPROP 0 LASTPIN (3375 1950) $PN DV42
J 2
(3365 1960);
DISPLAY 0.680851 (3365 1960);
PAINT MONO (3365 1960);
FORCEPROP 0 LASTPIN (3375 2600) $PN DW21
J 2
(3365 2610);
DISPLAY 0.680851 (3365 2610);
PAINT MONO (3365 2610);
FORCEPROP 0 LASTPIN (3375 3550) $PN DW60
J 2
(3365 3560);
DISPLAY 0.680851 (3365 3560);
PAINT MONO (3365 3560);
FORCEPROP 0 LASTPIN (5775 -200) $PN DM12
J 0
(5785 -190);
DISPLAY 0.680851 (5785 -190);
PAINT MONO (5785 -190);
FORCEPROP 0 LASTPIN (5775 -150) $PN DM16
J 0
(5785 -140);
DISPLAY 0.680851 (5785 -140);
PAINT MONO (5785 -140);
FORCEPROP 0 LASTPIN (5775 -100) $PN DM18
J 0
(5785 -90);
DISPLAY 0.680851 (5785 -90);
PAINT MONO (5785 -90);
FORCEPROP 0 LASTPIN (5775 -50) $PN DM20
J 0
(5785 -40);
DISPLAY 0.680851 (5785 -40);
PAINT MONO (5785 -40);
FORCEPROP 0 LASTPIN (5775 0) $PN DM22
J 0
(5785 10);
DISPLAY 0.680851 (5785 10);
PAINT MONO (5785 10);
FORCEPROP 0 LASTPIN (5775 50) $PN DM24
J 0
(5785 60);
DISPLAY 0.680851 (5785 60);
PAINT MONO (5785 60);
FORCEPROP 0 LASTPIN (5775 100) $PN DM26
J 0
(5785 110);
DISPLAY 0.680851 (5785 110);
PAINT MONO (5785 110);
FORCEPROP 0 LASTPIN (5775 150) $PN DM28
J 0
(5785 160);
DISPLAY 0.680851 (5785 160);
PAINT MONO (5785 160);
FORCEPROP 0 LASTPIN (5775 200) $PN DM30
J 0
(5785 210);
DISPLAY 0.680851 (5785 210);
PAINT MONO (5785 210);
FORCEPROP 0 LASTPIN (5775 250) $PN DM32
J 0
(5785 260);
DISPLAY 0.680851 (5785 260);
PAINT MONO (5785 260);
FORCEPROP 0 LASTPIN (5775 300) $PN DM34
J 0
(5785 310);
DISPLAY 0.680851 (5785 310);
PAINT MONO (5785 310);
FORCEPROP 0 LASTPIN (5775 350) $PN DM36
J 0
(5785 360);
DISPLAY 0.680851 (5785 360);
PAINT MONO (5785 360);
FORCEPROP 0 LASTPIN (5775 400) $PN DM38
J 0
(5785 410);
DISPLAY 0.680851 (5785 410);
PAINT MONO (5785 410);
FORCEPROP 0 LASTPIN (5775 -300) $PN DM4
J 0
(5785 -290);
DISPLAY 0.680851 (5785 -290);
PAINT MONO (5785 -290);
FORCEPROP 0 LASTPIN (5775 450) $PN DM40
J 0
(5785 460);
DISPLAY 0.680851 (5785 460);
PAINT MONO (5785 460);
FORCEPROP 0 LASTPIN (5775 500) $PN DM42
J 0
(5785 510);
DISPLAY 0.680851 (5785 510);
PAINT MONO (5785 510);
FORCEPROP 0 LASTPIN (5775 550) $PN DM44
J 0
(5785 560);
DISPLAY 0.680851 (5785 560);
PAINT MONO (5785 560);
FORCEPROP 0 LASTPIN (5775 600) $PN DM47
J 0
(5785 610);
DISPLAY 0.680851 (5785 610);
PAINT MONO (5785 610);
FORCEPROP 0 LASTPIN (5775 650) $PN DM49
J 0
(5785 660);
DISPLAY 0.680851 (5785 660);
PAINT MONO (5785 660);
FORCEPROP 0 LASTPIN (5775 750) $PN DM53
J 0
(5785 760);
DISPLAY 0.680851 (5785 760);
PAINT MONO (5785 760);
FORCEPROP 0 LASTPIN (5775 800) $PN DM55
J 0
(5785 810);
DISPLAY 0.680851 (5785 810);
PAINT MONO (5785 810);
FORCEPROP 0 LASTPIN (5775 850) $PN DM57
J 0
(5785 860);
DISPLAY 0.680851 (5785 860);
PAINT MONO (5785 860);
FORCEPROP 0 LASTPIN (5775 900) $PN DM59
J 0
(5785 910);
DISPLAY 0.680851 (5785 910);
PAINT MONO (5785 910);
FORCEPROP 0 LASTPIN (5775 950) $PN DM61
J 0
(5785 960);
DISPLAY 0.680851 (5785 960);
PAINT MONO (5785 960);
FORCEPROP 0 LASTPIN (5775 1000) $PN DM63
J 0
(5785 1010);
DISPLAY 0.680851 (5785 1010);
PAINT MONO (5785 1010);
FORCEPROP 0 LASTPIN (5775 1050) $PN DM65
J 0
(5785 1060);
DISPLAY 0.680851 (5785 1060);
PAINT MONO (5785 1060);
FORCEPROP 0 LASTPIN (5775 1100) $PN DM67
J 0
(5785 1110);
DISPLAY 0.680851 (5785 1110);
PAINT MONO (5785 1110);
FORCEPROP 0 LASTPIN (5775 1150) $PN DM69
J 0
(5785 1160);
DISPLAY 0.680851 (5785 1160);
PAINT MONO (5785 1160);
FORCEPROP 0 LASTPIN (5775 1200) $PN DM71
J 0
(5785 1210);
DISPLAY 0.680851 (5785 1210);
PAINT MONO (5785 1210);
FORCEPROP 0 LASTPIN (5775 1300) $PN DM75
J 0
(5785 1310);
DISPLAY 0.680851 (5785 1310);
PAINT MONO (5785 1310);
FORCEPROP 0 LASTPIN (5775 1350) $PN DM77
J 0
(5785 1360);
DISPLAY 0.680851 (5785 1360);
PAINT MONO (5785 1360);
FORCEPROP 0 LASTPIN (5775 1400) $PN DM79
J 0
(5785 1410);
DISPLAY 0.680851 (5785 1410);
PAINT MONO (5785 1410);
FORCEPROP 0 LASTPIN (5775 -250) $PN DM8
J 0
(5785 -240);
DISPLAY 0.680851 (5785 -240);
PAINT MONO (5785 -240);
FORCEPROP 0 LASTPIN (5775 1600) $PN DN78
J 0
(5785 1610);
DISPLAY 0.680851 (5785 1610);
PAINT MONO (5785 1610);
FORCEPROP 0 LASTPIN (5775 1650) $PN DN84
J 0
(5785 1660);
DISPLAY 0.680851 (5785 1660);
PAINT MONO (5785 1660);
FORCEPROP 0 LASTPIN (5775 1700) $PN DN88
J 0
(5785 1710);
DISPLAY 0.680851 (5785 1710);
PAINT MONO (5785 1710);
FORCEPROP 0 LASTPIN (5775 1900) $PN DP16
J 0
(5785 1910);
DISPLAY 0.680851 (5785 1910);
PAINT MONO (5785 1910);
FORCEPROP 0 LASTPIN (5775 2050) $PN DP30
J 0
(5785 2060);
DISPLAY 0.680851 (5785 2060);
PAINT MONO (5785 2060);
FORCEPROP 0 LASTPIN (5775 2100) $PN DP36
J 0
(5785 2110);
DISPLAY 0.680851 (5785 2110);
PAINT MONO (5785 2110);
FORCEPROP 0 LASTPIN (5775 1750) $PN DP4
J 0
(5785 1760);
DISPLAY 0.680851 (5785 1760);
PAINT MONO (5785 1760);
FORCEPROP 0 LASTPIN (5775 2200) $PN DP49
J 0
(5785 2210);
DISPLAY 0.680851 (5785 2210);
PAINT MONO (5785 2210);
FORCEPROP 0 LASTPIN (5775 2400) $PN DP73
J 0
(5785 2410);
DISPLAY 0.680851 (5785 2410);
PAINT MONO (5785 2410);
FORCEPROP 0 LASTPIN (5775 1800) $PN DP8
J 0
(5785 1810);
DISPLAY 0.680851 (5785 1810);
PAINT MONO (5785 1810);
FORCEPROP 0 LASTPIN (5775 2450) $PN DP81
J 0
(5785 2460);
DISPLAY 0.680851 (5785 2460);
PAINT MONO (5785 2460);
FORCEPROP 0 LASTPIN (5775 2500) $PN DP87
J 0
(5785 2510);
DISPLAY 0.680851 (5785 2510);
PAINT MONO (5785 2510);
FORCEPROP 0 LASTPIN (5775 2600) $PN DR1
J 0
(5785 2610);
DISPLAY 0.680851 (5785 2610);
PAINT MONO (5785 2610);
FORCEPROP 0 LASTPIN (5775 2750) $PN DR13
J 0
(5785 2760);
DISPLAY 0.680851 (5785 2760);
PAINT MONO (5785 2760);
FORCEPROP 0 LASTPIN (5775 2800) $PN DR19
J 0
(5785 2810);
DISPLAY 0.680851 (5785 2810);
PAINT MONO (5785 2810);
FORCEPROP 0 LASTPIN (5775 2850) $PN DR23
J 0
(5785 2860);
DISPLAY 0.680851 (5785 2860);
PAINT MONO (5785 2860);
FORCEPROP 0 LASTPIN (5775 2950) $PN DR29
J 0
(5785 2960);
DISPLAY 0.680851 (5785 2960);
PAINT MONO (5785 2960);
FORCEPROP 0 LASTPIN (5775 3000) $PN DR31
J 0
(5785 3010);
DISPLAY 0.680851 (5785 3010);
PAINT MONO (5785 3010);
FORCEPROP 0 LASTPIN (5775 3100) $PN DR37
J 0
(5785 3110);
DISPLAY 0.680851 (5785 3110);
PAINT MONO (5785 3110);
FORCEPROP 0 LASTPIN (5775 3150) $PN DR41
J 0
(5785 3160);
DISPLAY 0.680851 (5785 3160);
PAINT MONO (5785 3160);
FORCEPROP 0 LASTPIN (5775 3200) $PN DR43
J 0
(5785 3210);
DISPLAY 0.680851 (5785 3210);
PAINT MONO (5785 3210);
FORCEPROP 0 LASTPIN (5775 3250) $PN DR48
J 0
(5785 3260);
DISPLAY 0.680851 (5785 3260);
PAINT MONO (5785 3260);
FORCEPROP 0 LASTPIN (5775 3300) $PN DR50
J 0
(5785 3310);
DISPLAY 0.680851 (5785 3310);
PAINT MONO (5785 3310);
FORCEPROP 0 LASTPIN (5775 3400) $PN DR56
J 0
(5785 3410);
DISPLAY 0.680851 (5785 3410);
PAINT MONO (5785 3410);
FORCEPROP 0 LASTPIN (5775 3550) $PN DR66
J 0
(5785 3560);
DISPLAY 0.680851 (5785 3560);
PAINT MONO (5785 3560);
FORCEPROP 0 LASTPIN (3375 -300) $PN DR74
J 2
(3365 -290);
DISPLAY 0.680851 (3365 -290);
PAINT MONO (3365 -290);
FORCEPROP 0 LASTPIN (3375 -250) $PN DR78
J 2
(3365 -240);
DISPLAY 0.680851 (3365 -240);
PAINT MONO (3365 -240);
FORCEPROP 0 LASTPIN (3375 -200) $PN DR84
J 2
(3365 -190);
DISPLAY 0.680851 (3365 -190);
PAINT MONO (3365 -190);
FORCEPROP 0 LASTPIN (3375 -150) $PN DR88
J 2
(3365 -140);
DISPLAY 0.680851 (3365 -140);
PAINT MONO (3365 -140);
FORCEPROP 0 LASTPIN (5775 2700) $PN DR9
J 0
(5785 2710);
DISPLAY 0.680851 (5785 2710);
PAINT MONO (5785 2710);
FORCEPROP 0 LASTPIN (3375 0) $PN DT12
J 2
(3365 10);
DISPLAY 0.680851 (3365 10);
PAINT MONO (3365 10);
FORCEPROP 0 LASTPIN (3375 150) $PN DT22
J 2
(3365 160);
DISPLAY 0.680851 (3365 160);
PAINT MONO (3365 160);
FORCEPROP 0 LASTPIN (3375 250) $PN DT28
J 2
(3365 260);
DISPLAY 0.680851 (3365 260);
PAINT MONO (3365 260);
FORCEPROP 0 LASTPIN (3375 300) $PN DT32
J 2
(3365 310);
DISPLAY 0.680851 (3365 310);
PAINT MONO (3365 310);
FORCEPROP 0 LASTPIN (3375 350) $PN DT34
J 2
(3365 360);
DISPLAY 0.680851 (3365 360);
PAINT MONO (3365 360);
FORCEPROP 0 LASTPIN (3375 400) $PN DT38
J 2
(3365 410);
DISPLAY 0.680851 (3365 410);
PAINT MONO (3365 410);
FORCEPROP 0 LASTPIN (3375 450) $PN DT40
J 2
(3365 460);
DISPLAY 0.680851 (3365 460);
PAINT MONO (3365 460);
FORCEPROP 0 LASTPIN (3375 550) $PN DT47
J 2
(3365 560);
DISPLAY 0.680851 (3365 560);
PAINT MONO (3365 560);
FORCEPROP 0 LASTPIN (3375 700) $PN DT57
J 2
(3365 710);
DISPLAY 0.680851 (3365 710);
PAINT MONO (3365 710);
FORCEPROP 0 LASTPIN (3375 850) $PN DT65
J 2
(3365 860);
DISPLAY 0.680851 (3365 860);
PAINT MONO (3365 860);
FORCEPROP 0 LASTPIN (3375 900) $PN DT69
J 2
(3365 910);
DISPLAY 0.680851 (3365 910);
PAINT MONO (3365 910);
FORCEPROP 0 LASTPIN (3375 950) $PN DT71
J 2
(3365 960);
DISPLAY 0.680851 (3365 960);
PAINT MONO (3365 960);
FORCEPROP 0 LASTPIN (3375 1000) $PN DT75
J 2
(3365 1010);
DISPLAY 0.680851 (3365 1010);
PAINT MONO (3365 1010);
FORCEPROP 0 LASTPIN (3375 -50) $PN DT8
J 2
(3365 -40);
DISPLAY 0.680851 (3365 -40);
PAINT MONO (3365 -40);
FORCEPROP 0 LASTPIN (3375 1100) $PN DU21
J 2
(3365 1110);
DISPLAY 0.680851 (3365 1110);
PAINT MONO (3365 1110);
FORCEPROP 0 LASTPIN (3375 1150) $PN DU27
J 2
(3365 1160);
DISPLAY 0.680851 (3365 1160);
PAINT MONO (3365 1160);
FORCEPROP 0 LASTPIN (3375 1200) $PN DU33
J 2
(3365 1210);
DISPLAY 0.680851 (3365 1210);
PAINT MONO (3365 1210);
FORCEPROP 0 LASTPIN (3375 1550) $PN DU76
J 2
(3365 1560);
DISPLAY 0.680851 (3365 1560);
PAINT MONO (3365 1560);
FORCEPROP 0 LASTPIN (3375 1600) $PN DU78
J 2
(3365 1610);
DISPLAY 0.680851 (3365 1610);
PAINT MONO (3365 1610);
FORCEPROP 0 LASTPIN (3375 1650) $PN DU84
J 2
(3365 1660);
DISPLAY 0.680851 (3365 1660);
PAINT MONO (3365 1660);
FORCEPROP 0 LASTPIN (3375 1700) $PN DU88
J 2
(3365 1710);
DISPLAY 0.680851 (3365 1710);
PAINT MONO (3365 1710);
FORCEPROP 0 LASTPIN (3375 2000) $PN DV77
J 2
(3365 2010);
DISPLAY 0.680851 (3365 2010);
PAINT MONO (3365 2010);
FORCEPROP 0 LASTPIN (3375 2050) $PN DV79
J 2
(3365 2060);
DISPLAY 0.680851 (3365 2060);
PAINT MONO (3365 2060);
FORCEPROP 0 LASTPIN (3375 1800) $PN DV8
J 2
(3365 1810);
DISPLAY 0.680851 (3365 1810);
PAINT MONO (3365 1810);
FORCEPROP 0 LASTPIN (3375 2100) $PN DV81
J 2
(3365 2110);
DISPLAY 0.680851 (3365 2110);
PAINT MONO (3365 2110);
FORCEPROP 0 LASTPIN (3375 2150) $PN DV83
J 2
(3365 2160);
DISPLAY 0.680851 (3365 2160);
PAINT MONO (3365 2160);
FORCEPROP 0 LASTPIN (3375 2200) $PN DV87
J 2
(3365 2210);
DISPLAY 0.680851 (3365 2210);
PAINT MONO (3365 2210);
FORCEPROP 0 LASTPIN (3375 2250) $PN DV91
J 2
(3365 2260);
DISPLAY 0.680851 (3365 2260);
PAINT MONO (3365 2260);
FORCEPROP 0 LASTPIN (3375 2300) $PN DW1
J 2
(3365 2310);
DISPLAY 0.680851 (3365 2310);
PAINT MONO (3365 2310);
FORCEPROP 0 LASTPIN (3375 2450) $PN DW13
J 2
(3365 2460);
DISPLAY 0.680851 (3365 2460);
PAINT MONO (3365 2460);
FORCEPROP 0 LASTPIN (3375 2500) $PN DW17
J 2
(3365 2510);
DISPLAY 0.680851 (3365 2510);
PAINT MONO (3365 2510);
FORCEPROP 0 LASTPIN (3375 2550) $PN DW19
J 2
(3365 2560);
DISPLAY 0.680851 (3365 2560);
PAINT MONO (3365 2560);
FORCEPROP 0 LASTPIN (3375 2650) $PN DW23
J 2
(3365 2660);
DISPLAY 0.680851 (3365 2660);
PAINT MONO (3365 2660);
FORCEPROP 0 LASTPIN (3375 2700) $PN DW25
J 2
(3365 2710);
DISPLAY 0.680851 (3365 2710);
PAINT MONO (3365 2710);
FORCEPROP 0 LASTPIN (3375 2750) $PN DW27
J 2
(3365 2760);
DISPLAY 0.680851 (3365 2760);
PAINT MONO (3365 2760);
FORCEPROP 0 LASTPIN (3375 2800) $PN DW29
J 2
(3365 2810);
DISPLAY 0.680851 (3365 2810);
PAINT MONO (3365 2810);
FORCEPROP 0 LASTPIN (3375 2850) $PN DW31
J 2
(3365 2860);
DISPLAY 0.680851 (3365 2860);
PAINT MONO (3365 2860);
FORCEPROP 0 LASTPIN (3375 2900) $PN DW33
J 2
(3365 2910);
DISPLAY 0.680851 (3365 2910);
PAINT MONO (3365 2910);
FORCEPROP 0 LASTPIN (3375 2950) $PN DW35
J 2
(3365 2960);
DISPLAY 0.680851 (3365 2960);
PAINT MONO (3365 2960);
FORCEPROP 0 LASTPIN (3375 3000) $PN DW37
J 2
(3365 3010);
DISPLAY 0.680851 (3365 3010);
PAINT MONO (3365 3010);
FORCEPROP 0 LASTPIN (3375 3050) $PN DW39
J 2
(3365 3060);
DISPLAY 0.680851 (3365 3060);
PAINT MONO (3365 3060);
FORCEPROP 0 LASTPIN (3375 3100) $PN DW41
J 2
(3365 3110);
DISPLAY 0.680851 (3365 3110);
PAINT MONO (3365 3110);
FORCEPROP 0 LASTPIN (3375 3150) $PN DW43
J 2
(3365 3160);
DISPLAY 0.680851 (3365 3160);
PAINT MONO (3365 3160);
FORCEPROP 0 LASTPIN (3375 3200) $PN DW45
J 2
(3365 3210);
DISPLAY 0.680851 (3365 3210);
PAINT MONO (3365 3210);
FORCEPROP 0 LASTPIN (3375 3250) $PN DW48
J 2
(3365 3260);
DISPLAY 0.680851 (3365 3260);
PAINT MONO (3365 3260);
FORCEPROP 0 LASTPIN (3375 2350) $PN DW5
J 2
(3365 2360);
DISPLAY 0.680851 (3365 2360);
PAINT MONO (3365 2360);
FORCEPROP 0 LASTPIN (3375 3300) $PN DW50
J 2
(3365 3310);
DISPLAY 0.680851 (3365 3310);
PAINT MONO (3365 3310);
FORCEPROP 0 LASTPIN (3375 3350) $PN DW52
J 2
(3365 3360);
DISPLAY 0.680851 (3365 3360);
PAINT MONO (3365 3360);
FORCEPROP 0 LASTPIN (3375 3400) $PN DW54
J 2
(3365 3410);
DISPLAY 0.680851 (3365 3410);
PAINT MONO (3365 3410);
FORCEPROP 0 LASTPIN (3375 3450) $PN DW56
J 2
(3365 3460);
DISPLAY 0.680851 (3365 3460);
PAINT MONO (3365 3460);
FORCEPROP 0 LASTPIN (3375 3500) $PN DW58
J 2
(3365 3510);
DISPLAY 0.680851 (3365 3510);
PAINT MONO (3365 3510);
FORCEPROP 0 LASTPIN (3375 3600) $PN DW62
J 2
(3365 3610);
DISPLAY 0.680851 (3365 3610);
PAINT MONO (3365 3610);
FORCEPROP 0 LASTPIN (3375 3650) $PN DW64
J 2
(3365 3660);
DISPLAY 0.680851 (3365 3660);
PAINT MONO (3365 3660);
FORCEPROP 0 LASTPIN (3375 2400) $PN DW9
J 2
(3365 2410);
DISPLAY 0.680851 (3365 2410);
PAINT MONO (3365 2410);
FORCEPROP 2 LAST CDS_LIB pure_quanta
J 0
(4575 1675);
DISPLAY INVISIBLE (4575 1675);
FORCEPROP 1 LAST NEEDS_NO_SIZE TRUE
J 0
(4575 1675);
DISPLAY 0.723404 (4575 1675);
PAINT GREEN (4575 1675);
DISPLAY INVISIBLE (4575 1675);
FORCEPROP 1 LAST CDS_LMAN_SYM_OUTLINE -1050,2150,1050,-2100
J 0
(4575 1675);
DISPLAY 0.468085 (4575 1675);
PAINT GREEN (4575 1675);
DISPLAY INVISIBLE (4575 1675);
FORCEPROP 2 LAST CDS_LOCATION U2
J 0
(3525 4150);
DISPLAY 1.021277 (3525 4150);
DISPLAY INVISIBLE (3525 4150);
FORCEPROP 0 LAST $SEC 33
J 0
(3525 4150);
DISPLAY 0.680851 (3525 4150);
PAINT MONO (3525 4150);
DISPLAY INVISIBLE (3525 4150);
FORCEPROP 2 LAST CDS_SEC 33
J 0
(3525 4150);
DISPLAY 1.021277 (3525 4150);
DISPLAY INVISIBLE (3525 4150);
FORCEPROP 1 LAST PATH I10
J 0
(4575 1675);
DISPLAY 0.723404 (4575 1675);
PAINT GREEN (4575 1675);
DISPLAY INVISIBLE (4575 1675);
FORCEADD UNIVERSAL_GND..1
(-2950 -850);
FORCEPROP 3 LASTPIN (-2950 -800) SIG_NAME GND\g
J 0
(-2940 -790);
DISPLAY 0.659574 (-2940 -790);
PAINT MONO (-2940 -790);
DISPLAY INVISIBLE (-2940 -790);
FORCEPROP 2 LAST CDS_LIB logical_power
J 0
(-2950 -850);
PAINT MONO (-2950 -850);
DISPLAY INVISIBLE (-2950 -850);
FORCEPROP 1 LAST HDL_POWER GND
J 1
(-2925 -925);
DISPLAY 0.872340 (-2925 -925);
PAINT GREEN (-2925 -925);
DISPLAY INVISIBLE (-2925 -925);
FORCEPROP 1 LAST PATH I2
J 0
(-2875 -850);
DISPLAY 0.872340 (-2875 -850);
PAINT AQUA (-2875 -850);
DISPLAY INVISIBLE (-2875 -850);
FORCEADD UNIVERSAL_GND..1
(-50 -850);
FORCEPROP 3 LASTPIN (-50 -800) SIG_NAME GND\g
J 0
(-40 -790);
DISPLAY 0.659574 (-40 -790);
PAINT MONO (-40 -790);
DISPLAY INVISIBLE (-40 -790);
FORCEPROP 2 LAST CDS_LIB logical_power
J 0
(-50 -850);
PAINT MONO (-50 -850);
DISPLAY INVISIBLE (-50 -850);
FORCEPROP 1 LAST HDL_POWER GND
J 1
(-25 -925);
DISPLAY 0.872340 (-25 -925);
PAINT GREEN (-25 -925);
DISPLAY INVISIBLE (-25 -925);
FORCEPROP 1 LAST PATH I3
J 0
(25 -850);
DISPLAY 0.872340 (25 -850);
PAINT AQUA (25 -850);
DISPLAY INVISIBLE (25 -850);
FORCEADD UNIVERSAL_GND..1
(3000 -850);
FORCEPROP 3 LASTPIN (3000 -800) SIG_NAME GND\g
J 0
(3010 -790);
DISPLAY 0.659574 (3010 -790);
PAINT MONO (3010 -790);
DISPLAY INVISIBLE (3010 -790);
FORCEPROP 2 LAST CDS_LIB logical_power
J 0
(3000 -850);
PAINT MONO (3000 -850);
DISPLAY INVISIBLE (3000 -850);
FORCEPROP 1 LAST HDL_POWER GND
J 1
(3025 -925);
DISPLAY 0.872340 (3025 -925);
PAINT GREEN (3025 -925);
DISPLAY INVISIBLE (3025 -925);
FORCEPROP 1 LAST PATH I5
J 0
(3075 -850);
DISPLAY 0.872340 (3075 -850);
PAINT AQUA (3075 -850);
DISPLAY INVISIBLE (3075 -850);
FORCEADD UNIVERSAL_GND..1
(100 -850);
FORCEPROP 3 LASTPIN (100 -800) SIG_NAME GND\g
J 0
(110 -790);
DISPLAY 0.659574 (110 -790);
PAINT MONO (110 -790);
DISPLAY INVISIBLE (110 -790);
FORCEPROP 2 LAST CDS_LIB logical_power
J 0
(100 -850);
PAINT MONO (100 -850);
DISPLAY INVISIBLE (100 -850);
FORCEPROP 1 LAST HDL_POWER GND
J 1
(125 -925);
DISPLAY 0.872340 (125 -925);
PAINT GREEN (125 -925);
DISPLAY INVISIBLE (125 -925);
FORCEPROP 1 LAST PATH I6
J 0
(175 -850);
DISPLAY 0.872340 (175 -850);
PAINT AQUA (175 -850);
DISPLAY INVISIBLE (175 -850);
FORCEADD UNIVERSAL_GND..1
(3125 -850);
FORCEPROP 3 LASTPIN (3125 -800) SIG_NAME GND\g
J 0
(3135 -790);
DISPLAY 0.659574 (3135 -790);
PAINT MONO (3135 -790);
DISPLAY INVISIBLE (3135 -790);
FORCEPROP 2 LAST CDS_LIB logical_power
J 0
(3125 -850);
PAINT MONO (3125 -850);
DISPLAY INVISIBLE (3125 -850);
FORCEPROP 1 LAST HDL_POWER GND
J 1
(3150 -925);
DISPLAY 0.872340 (3150 -925);
PAINT GREEN (3150 -925);
DISPLAY INVISIBLE (3150 -925);
FORCEPROP 1 LAST PATH I7
J 0
(3200 -850);
DISPLAY 0.872340 (3200 -850);
PAINT AQUA (3200 -850);
DISPLAY INVISIBLE (3200 -850);
FORCEADD UNIVERSAL_GND..1
(6025 -850);
FORCEPROP 3 LASTPIN (6025 -800) SIG_NAME GND\g
J 0
(6035 -790);
DISPLAY 0.659574 (6035 -790);
PAINT MONO (6035 -790);
DISPLAY INVISIBLE (6035 -790);
FORCEPROP 2 LAST CDS_LIB logical_power
J 0
(6025 -850);
PAINT MONO (6025 -850);
DISPLAY INVISIBLE (6025 -850);
FORCEPROP 1 LAST HDL_POWER GND
J 1
(6050 -925);
DISPLAY 0.872340 (6050 -925);
PAINT GREEN (6050 -925);
DISPLAY INVISIBLE (6050 -925);
FORCEPROP 1 LAST PATH I8
J 0
(6100 -850);
DISPLAY 0.872340 (6100 -850);
PAINT AQUA (6100 -850);
DISPLAY INVISIBLE (6100 -850);
FORCEADD SOCKET4677_AZIF0045P001C01CS..32
(1550 1675);
FORCEPROP 1 LAST PART_NUMBER DGA^7000023
J 0
(500 3925);
DISPLAY 0.723404 (500 3925);
PAINT GREEN (500 3925);
DISPLAY INVISIBLE (500 3925);
FORCEPROP 2 LAST PART_TYPE SMLF
J 0
(500 4100);
DISPLAY 1.021277 (500 4100);
FORCEPROP 1 LAST MATERIAL IO
J 0
(500 3850);
DISPLAY 0.723404 (500 3850);
PAINT GREEN (500 3850);
FORCEPROP 2 LAST VALUE SOCKET4677_AZIF0045-P001C01CS
J 0
(500 4050);
DISPLAY 1.021277 (500 4050);
FORCEPROP 1 LAST $LOCATION U2
J 0
(500 4000);
DISPLAY 0.723404 (500 4000);
PAINT GREEN (500 4000);
FORCEPROP 0 LASTPIN (2750 300) $PN DY12
J 0
(2760 310);
DISPLAY 0.680851 (2760 310);
PAINT MONO (2760 310);
FORCEPROP 0 LASTPIN (2750 350) $PN DY16
J 0
(2760 360);
DISPLAY 0.680851 (2760 360);
PAINT MONO (2760 360);
FORCEPROP 0 LASTPIN (2750 200) $PN DY4
J 0
(2760 210);
DISPLAY 0.680851 (2760 210);
PAINT MONO (2760 210);
FORCEPROP 0 LASTPIN (2750 400) $PN DY42
J 0
(2760 410);
DISPLAY 0.680851 (2760 410);
PAINT MONO (2760 410);
FORCEPROP 0 LASTPIN (2750 650) $PN EA39
J 0
(2760 660);
DISPLAY 0.680851 (2760 660);
PAINT MONO (2760 660);
FORCEPROP 0 LASTPIN (2750 700) $PN EA45
J 0
(2760 710);
DISPLAY 0.680851 (2760 710);
PAINT MONO (2760 710);
FORCEPROP 0 LASTPIN (2750 750) $PN EA52
J 0
(2760 760);
DISPLAY 0.680851 (2760 760);
PAINT MONO (2760 760);
FORCEPROP 0 LASTPIN (2750 800) $PN EA58
J 0
(2760 810);
DISPLAY 0.680851 (2760 810);
PAINT MONO (2760 810);
FORCEPROP 0 LASTPIN (2750 850) $PN EA64
J 0
(2760 860);
DISPLAY 0.680851 (2760 860);
PAINT MONO (2760 860);
FORCEPROP 0 LASTPIN (2750 1350) $PN EB16
J 0
(2760 1360);
DISPLAY 0.680851 (2760 1360);
PAINT MONO (2760 1360);
FORCEPROP 0 LASTPIN (2750 1400) $PN EB20
J 0
(2760 1410);
DISPLAY 0.680851 (2760 1410);
PAINT MONO (2760 1410);
FORCEPROP 0 LASTPIN (2750 1500) $PN EB26
J 0
(2760 1510);
DISPLAY 0.680851 (2760 1510);
PAINT MONO (2760 1510);
FORCEPROP 0 LASTPIN (2750 1650) $PN EB34
J 0
(2760 1660);
DISPLAY 0.680851 (2760 1660);
PAINT MONO (2760 1660);
FORCEPROP 0 LASTPIN (2750 1200) $PN EB4
J 0
(2760 1210);
DISPLAY 0.680851 (2760 1210);
PAINT MONO (2760 1210);
FORCEPROP 0 LASTPIN (2750 1800) $PN EB44
J 0
(2760 1810);
DISPLAY 0.680851 (2760 1810);
PAINT MONO (2760 1810);
FORCEPROP 0 LASTPIN (2750 1900) $PN EB51
J 0
(2760 1910);
DISPLAY 0.680851 (2760 1910);
PAINT MONO (2760 1910);
FORCEPROP 0 LASTPIN (2750 1950) $PN EB53
J 0
(2760 1960);
DISPLAY 0.680851 (2760 1960);
PAINT MONO (2760 1960);
FORCEPROP 0 LASTPIN (2750 2050) $PN EB59
J 0
(2760 2060);
DISPLAY 0.680851 (2760 2060);
PAINT MONO (2760 2060);
FORCEPROP 0 LASTPIN (2750 2100) $PN EB63
J 0
(2760 2110);
DISPLAY 0.680851 (2760 2110);
PAINT MONO (2760 2110);
FORCEPROP 0 LASTPIN (2750 2500) $PN EB91
J 0
(2760 2510);
DISPLAY 0.680851 (2760 2510);
PAINT MONO (2760 2510);
FORCEPROP 0 LASTPIN (2750 2850) $PN EC25
J 0
(2760 2860);
DISPLAY 0.680851 (2760 2860);
PAINT MONO (2760 2860);
FORCEPROP 0 LASTPIN (2750 3000) $PN EC35
J 0
(2760 3010);
DISPLAY 0.680851 (2760 3010);
PAINT MONO (2760 3010);
FORCEPROP 0 LASTPIN (2750 2600) $PN EC5
J 0
(2760 2610);
DISPLAY 0.680851 (2760 2610);
PAINT MONO (2760 2610);
FORCEPROP 0 LASTPIN (2750 3300) $PN EC54
J 0
(2760 3310);
DISPLAY 0.680851 (2760 3310);
PAINT MONO (2760 3310);
FORCEPROP 0 LASTPIN (2750 3400) $PN EC60
J 0
(2760 3410);
DISPLAY 0.680851 (2760 3410);
PAINT MONO (2760 3410);
FORCEPROP 0 LASTPIN (2750 3450) $PN EC62
J 0
(2760 3460);
DISPLAY 0.680851 (2760 3460);
PAINT MONO (2760 3460);
FORCEPROP 0 LASTPIN (2750 3550) $PN EC68
J 0
(2760 3560);
DISPLAY 0.680851 (2760 3560);
PAINT MONO (2760 3560);
FORCEPROP 0 LASTPIN (350 -50) $PN ED12
J 2
(340 -40);
DISPLAY 0.680851 (340 -40);
PAINT MONO (340 -40);
FORCEPROP 0 LASTPIN (350 50) $PN ED18
J 2
(340 60);
DISPLAY 0.680851 (340 60);
PAINT MONO (340 60);
FORCEPROP 0 LASTPIN (350 250) $PN ED42
J 2
(340 260);
DISPLAY 0.680851 (340 260);
PAINT MONO (340 260);
FORCEPROP 0 LASTPIN (350 350) $PN ED55
J 2
(340 360);
DISPLAY 0.680851 (340 360);
PAINT MONO (340 360);
FORCEPROP 0 LASTPIN (350 400) $PN ED61
J 2
(340 410);
DISPLAY 0.680851 (340 410);
PAINT MONO (340 410);
FORCEPROP 0 LASTPIN (350 450) $PN ED67
J 2
(340 460);
DISPLAY 0.680851 (340 460);
PAINT MONO (340 460);
FORCEPROP 0 LASTPIN (350 500) $PN ED73
J 2
(340 510);
DISPLAY 0.680851 (340 510);
PAINT MONO (340 510);
FORCEPROP 0 LASTPIN (350 550) $PN EE17
J 2
(340 560);
DISPLAY 0.680851 (340 560);
PAINT MONO (340 560);
FORCEPROP 0 LASTPIN (350 600) $PN EE39
J 2
(340 610);
DISPLAY 0.680851 (340 610);
PAINT MONO (340 610);
FORCEPROP 0 LASTPIN (350 650) $PN EE52
J 2
(340 660);
DISPLAY 0.680851 (340 660);
PAINT MONO (340 660);
FORCEPROP 0 LASTPIN (2750 -300) $PN DW66
J 0
(2760 -290);
DISPLAY 0.680851 (2760 -290);
PAINT MONO (2760 -290);
FORCEPROP 0 LASTPIN (2750 -250) $PN DW68
J 0
(2760 -240);
DISPLAY 0.680851 (2760 -240);
PAINT MONO (2760 -240);
FORCEPROP 0 LASTPIN (2750 -200) $PN DW70
J 0
(2760 -190);
DISPLAY 0.680851 (2760 -190);
PAINT MONO (2760 -190);
FORCEPROP 0 LASTPIN (2750 -150) $PN DW72
J 0
(2760 -140);
DISPLAY 0.680851 (2760 -140);
PAINT MONO (2760 -140);
FORCEPROP 0 LASTPIN (2750 -100) $PN DW74
J 0
(2760 -90);
DISPLAY 0.680851 (2760 -90);
PAINT MONO (2760 -90);
FORCEPROP 0 LASTPIN (2750 -50) $PN DW76
J 0
(2760 -40);
DISPLAY 0.680851 (2760 -40);
PAINT MONO (2760 -40);
FORCEPROP 0 LASTPIN (2750 0) $PN DW80
J 0
(2760 10);
DISPLAY 0.680851 (2760 10);
PAINT MONO (2760 10);
FORCEPROP 0 LASTPIN (2750 50) $PN DW82
J 0
(2760 60);
DISPLAY 0.680851 (2760 60);
PAINT MONO (2760 60);
FORCEPROP 0 LASTPIN (350 1900) $PN EF51
J 2
(340 1910);
DISPLAY 0.680851 (340 1910);
PAINT MONO (340 1910);
FORCEPROP 0 LASTPIN (2750 100) $PN DW84
J 0
(2760 110);
DISPLAY 0.680851 (2760 110);
PAINT MONO (2760 110);
FORCEPROP 0 LASTPIN (2750 150) $PN DW88
J 0
(2760 160);
DISPLAY 0.680851 (2760 160);
PAINT MONO (2760 160);
FORCEPROP 0 LASTPIN (2750 450) $PN DY77
J 0
(2760 460);
DISPLAY 0.680851 (2760 460);
PAINT MONO (2760 460);
FORCEPROP 0 LASTPIN (2750 250) $PN DY8
J 0
(2760 260);
DISPLAY 0.680851 (2760 260);
PAINT MONO (2760 260);
FORCEPROP 0 LASTPIN (2750 500) $PN EA21
J 0
(2760 510);
DISPLAY 0.680851 (2760 510);
PAINT MONO (2760 510);
FORCEPROP 0 LASTPIN (2750 550) $PN EA27
J 0
(2760 560);
DISPLAY 0.680851 (2760 560);
PAINT MONO (2760 560);
FORCEPROP 0 LASTPIN (350 2450) $PN EF73
J 2
(340 2460);
DISPLAY 0.680851 (340 2460);
PAINT MONO (340 2460);
FORCEPROP 0 LASTPIN (350 2500) $PN EF75
J 2
(340 2510);
DISPLAY 0.680851 (340 2510);
PAINT MONO (340 2510);
FORCEPROP 0 LASTPIN (2750 600) $PN EA33
J 0
(2760 610);
DISPLAY 0.680851 (2760 610);
PAINT MONO (2760 610);
FORCEPROP 0 LASTPIN (2750 900) $PN EA70
J 0
(2760 910);
DISPLAY 0.680851 (2760 910);
PAINT MONO (2760 910);
FORCEPROP 0 LASTPIN (2750 950) $PN EA76
J 0
(2760 960);
DISPLAY 0.680851 (2760 960);
PAINT MONO (2760 960);
FORCEPROP 0 LASTPIN (2750 1000) $PN EA78
J 0
(2760 1010);
DISPLAY 0.680851 (2760 1010);
PAINT MONO (2760 1010);
FORCEPROP 0 LASTPIN (2750 1050) $PN EA80
J 0
(2760 1060);
DISPLAY 0.680851 (2760 1060);
PAINT MONO (2760 1060);
FORCEPROP 0 LASTPIN (350 2700) $PN EF89
J 2
(340 2710);
DISPLAY 0.680851 (340 2710);
PAINT MONO (340 2710);
FORCEPROP 0 LASTPIN (350 2900) $PN EG13
J 2
(340 2910);
DISPLAY 0.680851 (340 2910);
PAINT MONO (340 2910);
FORCEPROP 0 LASTPIN (2750 1100) $PN EA84
J 0
(2760 1110);
DISPLAY 0.680851 (2760 1110);
PAINT MONO (2760 1110);
FORCEPROP 0 LASTPIN (2750 1150) $PN EA88
J 0
(2760 1160);
DISPLAY 0.680851 (2760 1160);
PAINT MONO (2760 1160);
FORCEPROP 0 LASTPIN (2750 1300) $PN EB12
J 0
(2760 1310);
DISPLAY 0.680851 (2760 1310);
PAINT MONO (2760 1310);
FORCEPROP 0 LASTPIN (2750 1450) $PN EB22
J 0
(2760 1460);
DISPLAY 0.680851 (2760 1460);
PAINT MONO (2760 1460);
FORCEPROP 0 LASTPIN (2750 1550) $PN EB28
J 0
(2760 1560);
DISPLAY 0.680851 (2760 1560);
PAINT MONO (2760 1560);
FORCEPROP 0 LASTPIN (350 2750) $PN EG5
J 2
(340 2760);
DISPLAY 0.680851 (340 2760);
PAINT MONO (340 2760);
FORCEPROP 0 LASTPIN (350 3000) $PN EG52
J 2
(340 3010);
DISPLAY 0.680851 (340 3010);
PAINT MONO (340 3010);
FORCEPROP 0 LASTPIN (2750 1600) $PN EB32
J 0
(2760 1610);
DISPLAY 0.680851 (2760 1610);
PAINT MONO (2760 1610);
FORCEPROP 0 LASTPIN (2750 1700) $PN EB38
J 0
(2760 1710);
DISPLAY 0.680851 (2760 1710);
PAINT MONO (2760 1710);
FORCEPROP 0 LASTPIN (350 2800) $PN EG7
J 2
(340 2810);
DISPLAY 0.680851 (340 2810);
PAINT MONO (340 2810);
FORCEPROP 0 LASTPIN (2750 1750) $PN EB40
J 0
(2760 1760);
DISPLAY 0.680851 (2760 1760);
PAINT MONO (2760 1760);
FORCEPROP 0 LASTPIN (2750 1850) $PN EB47
J 0
(2760 1860);
DISPLAY 0.680851 (2760 1860);
PAINT MONO (2760 1860);
FORCEPROP 0 LASTPIN (2750 2000) $PN EB57
J 0
(2760 2010);
DISPLAY 0.680851 (2760 2010);
PAINT MONO (2760 2010);
FORCEPROP 0 LASTPIN (2750 2150) $PN EB65
J 0
(2760 2160);
DISPLAY 0.680851 (2760 2160);
PAINT MONO (2760 2160);
FORCEPROP 0 LASTPIN (2750 2200) $PN EB69
J 0
(2760 2210);
DISPLAY 0.680851 (2760 2210);
PAINT MONO (2760 2210);
FORCEPROP 0 LASTPIN (2750 2250) $PN EB71
J 0
(2760 2260);
DISPLAY 0.680851 (2760 2260);
PAINT MONO (2760 2260);
FORCEPROP 0 LASTPIN (2750 2300) $PN EB75
J 0
(2760 2310);
DISPLAY 0.680851 (2760 2310);
PAINT MONO (2760 2310);
FORCEPROP 0 LASTPIN (350 3400) $PN EH12
J 2
(340 3410);
DISPLAY 0.680851 (340 3410);
PAINT MONO (340 3410);
FORCEPROP 0 LASTPIN (350 3450) $PN EH14
J 2
(340 3460);
DISPLAY 0.680851 (340 3460);
PAINT MONO (340 3460);
FORCEPROP 0 LASTPIN (2750 2350) $PN EB79
J 0
(2760 2360);
DISPLAY 0.680851 (2760 2360);
PAINT MONO (2760 2360);
FORCEPROP 0 LASTPIN (350 3550) $PN EH18
J 2
(340 3560);
DISPLAY 0.680851 (340 3560);
PAINT MONO (340 3560);
FORCEPROP 0 LASTPIN (2750 1250) $PN EB8
J 0
(2760 1260);
DISPLAY 0.680851 (2760 1260);
PAINT MONO (2760 1260);
FORCEPROP 0 LASTPIN (2750 2400) $PN EB83
J 0
(2760 2410);
DISPLAY 0.680851 (2760 2410);
PAINT MONO (2760 2410);
FORCEPROP 0 LASTPIN (2750 2450) $PN EB87
J 0
(2760 2460);
DISPLAY 0.680851 (2760 2460);
PAINT MONO (2760 2460);
FORCEPROP 0 LASTPIN (2750 2550) $PN EC1
J 0
(2760 2560);
DISPLAY 0.680851 (2760 2560);
PAINT MONO (2760 2560);
FORCEPROP 0 LASTPIN (2750 2700) $PN EC13
J 0
(2760 2710);
DISPLAY 0.680851 (2760 2710);
PAINT MONO (2760 2710);
FORCEPROP 0 LASTPIN (2750 2750) $PN EC19
J 0
(2760 2760);
DISPLAY 0.680851 (2760 2760);
PAINT MONO (2760 2760);
FORCEPROP 0 LASTPIN (2750 2800) $PN EC23
J 0
(2760 2810);
DISPLAY 0.680851 (2760 2810);
PAINT MONO (2760 2810);
FORCEPROP 0 LASTPIN (2750 2900) $PN EC29
J 0
(2760 2910);
DISPLAY 0.680851 (2760 2910);
PAINT MONO (2760 2910);
FORCEPROP 0 LASTPIN (2750 2950) $PN EC31
J 0
(2760 2960);
DISPLAY 0.680851 (2760 2960);
PAINT MONO (2760 2960);
FORCEPROP 0 LASTPIN (2750 3050) $PN EC37
J 0
(2760 3060);
DISPLAY 0.680851 (2760 3060);
PAINT MONO (2760 3060);
FORCEPROP 0 LASTPIN (350 3350) $PN EH6
J 2
(340 3360);
DISPLAY 0.680851 (340 3360);
PAINT MONO (340 3360);
FORCEPROP 0 LASTPIN (2750 3100) $PN EC41
J 0
(2760 3110);
DISPLAY 0.680851 (2760 3110);
PAINT MONO (2760 3110);
FORCEPROP 0 LASTPIN (2750 3150) $PN EC43
J 0
(2760 3160);
DISPLAY 0.680851 (2760 3160);
PAINT MONO (2760 3160);
FORCEPROP 0 LASTPIN (2750 3200) $PN EC48
J 0
(2760 3210);
DISPLAY 0.680851 (2760 3210);
PAINT MONO (2760 3210);
FORCEPROP 0 LASTPIN (2750 3250) $PN EC50
J 0
(2760 3260);
DISPLAY 0.680851 (2760 3260);
PAINT MONO (2760 3260);
FORCEPROP 0 LASTPIN (2750 3350) $PN EC56
J 0
(2760 3360);
DISPLAY 0.680851 (2760 3360);
PAINT MONO (2760 3360);
FORCEPROP 0 LASTPIN (2750 3500) $PN EC66
J 0
(2760 3510);
DISPLAY 0.680851 (2760 3510);
PAINT MONO (2760 3510);
FORCEPROP 0 LASTPIN (2750 3600) $PN EC72
J 0
(2760 3610);
DISPLAY 0.680851 (2760 3610);
PAINT MONO (2760 3610);
FORCEPROP 0 LASTPIN (2750 3650) $PN EC74
J 0
(2760 3660);
DISPLAY 0.680851 (2760 3660);
PAINT MONO (2760 3660);
FORCEPROP 0 LASTPIN (350 -300) $PN EC82
J 2
(340 -290);
DISPLAY 0.680851 (340 -290);
PAINT MONO (340 -290);
FORCEPROP 0 LASTPIN (350 -250) $PN EC84
J 2
(340 -240);
DISPLAY 0.680851 (340 -240);
PAINT MONO (340 -240);
FORCEPROP 0 LASTPIN (350 -200) $PN EC88
J 2
(340 -190);
DISPLAY 0.680851 (340 -190);
PAINT MONO (340 -190);
FORCEPROP 0 LASTPIN (2750 2650) $PN EC9
J 0
(2760 2660);
DISPLAY 0.680851 (2760 2660);
PAINT MONO (2760 2660);
FORCEPROP 0 LASTPIN (350 0) $PN ED16
J 2
(340 10);
DISPLAY 0.680851 (340 10);
PAINT MONO (340 10);
FORCEPROP 0 LASTPIN (350 100) $PN ED24
J 2
(340 110);
DISPLAY 0.680851 (340 110);
PAINT MONO (340 110);
FORCEPROP 0 LASTPIN (350 150) $PN ED30
J 2
(340 160);
DISPLAY 0.680851 (340 160);
PAINT MONO (340 160);
FORCEPROP 0 LASTPIN (350 200) $PN ED36
J 2
(340 210);
DISPLAY 0.680851 (340 210);
PAINT MONO (340 210);
FORCEPROP 0 LASTPIN (350 -150) $PN ED4
J 2
(340 -140);
DISPLAY 0.680851 (340 -140);
PAINT MONO (340 -140);
FORCEPROP 0 LASTPIN (350 300) $PN ED49
J 2
(340 310);
DISPLAY 0.680851 (340 310);
PAINT MONO (340 310);
FORCEPROP 0 LASTPIN (350 -100) $PN ED8
J 2
(340 -90);
DISPLAY 0.680851 (340 -90);
PAINT MONO (340 -90);
FORCEPROP 0 LASTPIN (350 700) $PN EE78
J 2
(340 710);
DISPLAY 0.680851 (340 710);
PAINT MONO (340 710);
FORCEPROP 0 LASTPIN (350 750) $PN EE80
J 2
(340 760);
DISPLAY 0.680851 (340 760);
PAINT MONO (340 760);
FORCEPROP 0 LASTPIN (350 800) $PN EE88
J 2
(340 810);
DISPLAY 0.680851 (340 810);
PAINT MONO (340 810);
FORCEPROP 0 LASTPIN (350 1000) $PN EF12
J 2
(340 1010);
DISPLAY 0.680851 (340 1010);
PAINT MONO (340 1010);
FORCEPROP 0 LASTPIN (350 1050) $PN EF16
J 2
(340 1060);
DISPLAY 0.680851 (340 1060);
PAINT MONO (340 1060);
FORCEPROP 0 LASTPIN (350 1100) $PN EF18
J 2
(340 1110);
DISPLAY 0.680851 (340 1110);
PAINT MONO (340 1110);
FORCEPROP 0 LASTPIN (350 850) $PN EF2
J 2
(340 860);
DISPLAY 0.680851 (340 860);
PAINT MONO (340 860);
FORCEPROP 0 LASTPIN (350 1150) $PN EF20
J 2
(340 1160);
DISPLAY 0.680851 (340 1160);
PAINT MONO (340 1160);
FORCEPROP 0 LASTPIN (350 1200) $PN EF22
J 2
(340 1210);
DISPLAY 0.680851 (340 1210);
PAINT MONO (340 1210);
FORCEPROP 0 LASTPIN (350 1250) $PN EF24
J 2
(340 1260);
DISPLAY 0.680851 (340 1260);
PAINT MONO (340 1260);
FORCEPROP 0 LASTPIN (350 1300) $PN EF26
J 2
(340 1310);
DISPLAY 0.680851 (340 1310);
PAINT MONO (340 1310);
FORCEPROP 0 LASTPIN (350 1350) $PN EF28
J 2
(340 1360);
DISPLAY 0.680851 (340 1360);
PAINT MONO (340 1360);
FORCEPROP 0 LASTPIN (350 1400) $PN EF30
J 2
(340 1410);
DISPLAY 0.680851 (340 1410);
PAINT MONO (340 1410);
FORCEPROP 0 LASTPIN (350 1450) $PN EF32
J 2
(340 1460);
DISPLAY 0.680851 (340 1460);
PAINT MONO (340 1460);
FORCEPROP 0 LASTPIN (350 1500) $PN EF34
J 2
(340 1510);
DISPLAY 0.680851 (340 1510);
PAINT MONO (340 1510);
FORCEPROP 0 LASTPIN (350 1550) $PN EF36
J 2
(340 1560);
DISPLAY 0.680851 (340 1560);
PAINT MONO (340 1560);
FORCEPROP 0 LASTPIN (350 1600) $PN EF38
J 2
(340 1610);
DISPLAY 0.680851 (340 1610);
PAINT MONO (340 1610);
FORCEPROP 0 LASTPIN (350 900) $PN EF4
J 2
(340 910);
DISPLAY 0.680851 (340 910);
PAINT MONO (340 910);
FORCEPROP 0 LASTPIN (350 1650) $PN EF40
J 2
(340 1660);
DISPLAY 0.680851 (340 1660);
PAINT MONO (340 1660);
FORCEPROP 0 LASTPIN (350 1700) $PN EF42
J 2
(340 1710);
DISPLAY 0.680851 (340 1710);
PAINT MONO (340 1710);
FORCEPROP 0 LASTPIN (350 1750) $PN EF44
J 2
(340 1760);
DISPLAY 0.680851 (340 1760);
PAINT MONO (340 1760);
FORCEPROP 0 LASTPIN (350 1800) $PN EF47
J 2
(340 1810);
DISPLAY 0.680851 (340 1810);
PAINT MONO (340 1810);
FORCEPROP 0 LASTPIN (350 1850) $PN EF49
J 2
(340 1860);
DISPLAY 0.680851 (340 1860);
PAINT MONO (340 1860);
FORCEPROP 0 LASTPIN (350 1950) $PN EF53
J 2
(340 1960);
DISPLAY 0.680851 (340 1960);
PAINT MONO (340 1960);
FORCEPROP 0 LASTPIN (350 2000) $PN EF55
J 2
(340 2010);
DISPLAY 0.680851 (340 2010);
PAINT MONO (340 2010);
FORCEPROP 0 LASTPIN (350 2050) $PN EF57
J 2
(340 2060);
DISPLAY 0.680851 (340 2060);
PAINT MONO (340 2060);
FORCEPROP 0 LASTPIN (350 2100) $PN EF59
J 2
(340 2110);
DISPLAY 0.680851 (340 2110);
PAINT MONO (340 2110);
FORCEPROP 0 LASTPIN (350 2150) $PN EF61
J 2
(340 2160);
DISPLAY 0.680851 (340 2160);
PAINT MONO (340 2160);
FORCEPROP 0 LASTPIN (350 2200) $PN EF63
J 2
(340 2210);
DISPLAY 0.680851 (340 2210);
PAINT MONO (340 2210);
FORCEPROP 0 LASTPIN (350 2250) $PN EF65
J 2
(340 2260);
DISPLAY 0.680851 (340 2260);
PAINT MONO (340 2260);
FORCEPROP 0 LASTPIN (350 2300) $PN EF67
J 2
(340 2310);
DISPLAY 0.680851 (340 2310);
PAINT MONO (340 2310);
FORCEPROP 0 LASTPIN (350 2350) $PN EF69
J 2
(340 2360);
DISPLAY 0.680851 (340 2360);
PAINT MONO (340 2360);
FORCEPROP 0 LASTPIN (350 2400) $PN EF71
J 2
(340 2410);
DISPLAY 0.680851 (340 2410);
PAINT MONO (340 2410);
FORCEPROP 0 LASTPIN (350 2550) $PN EF77
J 2
(340 2560);
DISPLAY 0.680851 (340 2560);
PAINT MONO (340 2560);
FORCEPROP 0 LASTPIN (350 950) $PN EF8
J 2
(340 960);
DISPLAY 0.680851 (340 960);
PAINT MONO (340 960);
FORCEPROP 0 LASTPIN (350 2600) $PN EF85
J 2
(340 2610);
DISPLAY 0.680851 (340 2610);
PAINT MONO (340 2610);
FORCEPROP 0 LASTPIN (350 2650) $PN EF87
J 2
(340 2660);
DISPLAY 0.680851 (340 2660);
PAINT MONO (340 2660);
FORCEPROP 0 LASTPIN (350 2950) $PN EG39
J 2
(340 2960);
DISPLAY 0.680851 (340 2960);
PAINT MONO (340 2960);
FORCEPROP 0 LASTPIN (350 3050) $PN EG82
J 2
(340 3060);
DISPLAY 0.680851 (340 3060);
PAINT MONO (340 3060);
FORCEPROP 0 LASTPIN (350 3100) $PN EG84
J 2
(340 3110);
DISPLAY 0.680851 (340 3110);
PAINT MONO (340 3110);
FORCEPROP 0 LASTPIN (350 3150) $PN EG86
J 2
(340 3160);
DISPLAY 0.680851 (340 3160);
PAINT MONO (340 3160);
FORCEPROP 0 LASTPIN (350 3200) $PN EG88
J 2
(340 3210);
DISPLAY 0.680851 (340 3210);
PAINT MONO (340 3210);
FORCEPROP 0 LASTPIN (350 2850) $PN EG9
J 2
(340 2860);
DISPLAY 0.680851 (340 2860);
PAINT MONO (340 2860);
FORCEPROP 0 LASTPIN (350 3250) $PN EG90
J 2
(340 3260);
DISPLAY 0.680851 (340 3260);
PAINT MONO (340 3260);
FORCEPROP 0 LASTPIN (350 3500) $PN EH16
J 2
(340 3510);
DISPLAY 0.680851 (340 3510);
PAINT MONO (340 3510);
FORCEPROP 0 LASTPIN (350 3600) $PN EH24
J 2
(340 3610);
DISPLAY 0.680851 (340 3610);
PAINT MONO (340 3610);
FORCEPROP 0 LASTPIN (350 3650) $PN EH30
J 2
(340 3660);
DISPLAY 0.680851 (340 3660);
PAINT MONO (340 3660);
FORCEPROP 0 LASTPIN (350 3300) $PN EH4
J 2
(340 3310);
DISPLAY 0.680851 (340 3310);
PAINT MONO (340 3310);
FORCEPROP 2 LAST CDS_LIB pure_quanta
J 0
(1550 1675);
DISPLAY INVISIBLE (1550 1675);
FORCEPROP 1 LAST NEEDS_NO_SIZE TRUE
J 0
(1550 1675);
DISPLAY 0.723404 (1550 1675);
PAINT GREEN (1550 1675);
DISPLAY INVISIBLE (1550 1675);
FORCEPROP 1 LAST CDS_LMAN_SYM_OUTLINE -1050,2150,1050,-2100
J 0
(1550 1675);
DISPLAY 0.468085 (1550 1675);
PAINT GREEN (1550 1675);
DISPLAY INVISIBLE (1550 1675);
FORCEPROP 2 LAST CDS_LOCATION U2
J 0
(500 4150);
DISPLAY 1.021277 (500 4150);
DISPLAY INVISIBLE (500 4150);
FORCEPROP 0 LAST $SEC 32
J 0
(500 4150);
DISPLAY 0.680851 (500 4150);
PAINT MONO (500 4150);
DISPLAY INVISIBLE (500 4150);
FORCEPROP 2 LAST CDS_SEC 32
J 0
(500 4150);
DISPLAY 1.021277 (500 4150);
DISPLAY INVISIBLE (500 4150);
FORCEPROP 1 LAST PATH I9
J 0
(1550 1675);
DISPLAY 0.723404 (1550 1675);
PAINT GREEN (1550 1675);
DISPLAY INVISIBLE (1550 1675);
FORCEADD QUANTA_TITLE_BLOCK_C..1
(6225 -1700);
FORCEPROP 0 LAST CDS_CON_LAST_MODIFIED Fri Aug 25 14:00:22 2023
J 0
(4340 -1685);
PAINT MONO (4340 -1685);
DISPLAY INVISIBLE (4340 -1685);
FORCEPROP 2 LAST CUSTOM_TXT_CDS <XR_PAGE_TITLE>
J 0
(-1665 3550);
DISPLAY 0.638298 (-1665 3550);
PAINT PINK (-1665 3550);
DISPLAY INVISIBLE (-1665 3550);
FORCEPROP 2 LAST CUSTOM_TXT_CDS <CON_PAGE_NUM> OF <CON_TOTAL_PAGES>
J 0
(5750 -1675);
DISPLAY 0.978723 (5750 -1675);
FORCEPROP 2 LAST CUSTOM_TXT_CDS <Q_NUMBER>
J 0
(4822 -1597);
DISPLAY 1.212766 (4822 -1597);
FORCEPROP 2 LAST CUSTOM_TXT_CDS <CON_LAST_MODIFIED>
J 0
(4325 -1675);
DISPLAY 0.978723 (4325 -1675);
FORCEPROP 2 LAST CUSTOM_TXT_CDS <Q_PROJ>
J 0
(3843 -1598);
DISPLAY 1.212766 (3843 -1598);
FORCEPROP 2 LAST CUSTOM_TXT_CDS <Q_REV>
J 0
(6041 -1597);
DISPLAY 1.212766 (6041 -1597);
FORCEPROP 1 LAST CUSTOM_TXT_CDS <NAME_2>
J 0
(3050 -1650);
FORCEPROP 1 LAST CUSTOM_TXT_CDS <NAME_1>
J 0
(3050 -1525);
FORCEPROP 1 LAST Q_TITLE SPR CPU0 POWER - GND (27 OF 30)
J 0
(-3141 -1674);
DISPLAY 1.957447 (-3141 -1674);
PAINT GREEN (-3141 -1674);
FORCEPROP 1 LAST Q_DEPT 
J 1
(2462 -1651);
DISPLAY 1.957447 (2462 -1651);
PAINT GREEN (2462 -1651);
FORCEPROP 2 LAST CDS_LIB pure_quanta
J 0
(6225 -1700);
PAINT MONO (6225 -1700);
DISPLAY INVISIBLE (6225 -1700);
FORCEPROP 1 LAST CDS_LMAN_SYM_OUTLINE -9475,6775,100,-125
J 0
(6225 -1700);
DISPLAY 0.468085 (6225 -1700);
PAINT GREEN (6225 -1700);
DISPLAY INVISIBLE (6225 -1700);
FORCEPROP 2 LAST PAGE_BORDER TRUE
J 0
(-1665 3550);
DISPLAY 0.638298 (-1665 3550);
PAINT PINK (-1665 3550);
DISPLAY INVISIBLE (-1665 3550);
FORCEPROP 2 LAST CDS_XR_PAGE_TITLE CR-39 : @S9S_MB_2U_LIB.S9S_MB_2U(SCH_1):PAGE39
J 0
(-1665 3550);
DISPLAY 0.638298 (-1665 3550);
PAINT PINK (-1665 3550);
DISPLAY INVISIBLE (-1665 3550);
FORCEPROP 1 LAST COMMENT_BODY TRUE
J 0
(6237 -1713);
DISPLAY 0.978723 (6237 -1713);
PAINT GREEN (6237 -1713);
DISPLAY INVISIBLE (6237 -1713);
WIRE 16 -1 (6025 -300)(6025 -800);
WIRE 16 -1 (6025 -250)(6025 -300);
WIRE 16 -1 (5775 -300)(6025 -300);
WIRE 16 -1 (3125 -300)(3125 -800);
WIRE 16 -1 (3125 -250)(3125 -300);
WIRE 16 -1 (3125 -300)(3375 -300);
WIRE 16 -1 (100 -300)(100 -800);
WIRE 16 -1 (100 -250)(100 -300);
WIRE 16 -1 (100 -300)(350 -300);
WIRE 16 -1 (3000 -300)(3000 -800);
WIRE 16 -1 (3000 -250)(3000 -300);
WIRE 16 -1 (2750 -300)(3000 -300);
WIRE 16 -1 (-50 -300)(-50 -800);
WIRE 16 -1 (-50 -250)(-50 -300);
WIRE 16 -1 (-300 -300)(-50 -300);
WIRE 16 -1 (-2950 -300)(-2950 -800);
WIRE 16 -1 (-2950 -250)(-2950 -300);
WIRE 16 -1 (-2950 -300)(-2700 -300);
WIRE 16 -1 (-50 3650)(-300 3650);
WIRE 16 -1 (-50 3600)(-300 3600);
WIRE 16 -1 (-50 3650)(-50 3600);
WIRE 16 -1 (-50 3550)(-300 3550);
WIRE 16 -1 (-50 3600)(-50 3550);
WIRE 16 -1 (-50 3500)(-300 3500);
WIRE 16 -1 (-50 3550)(-50 3500);
WIRE 16 -1 (-300 3450)(-50 3450);
WIRE 16 -1 (-50 3450)(-50 3500);
WIRE 16 -1 (-50 3400)(-300 3400);
WIRE 16 -1 (-50 3400)(-50 3450);
WIRE 16 -1 (-50 3350)(-300 3350);
WIRE 16 -1 (-50 3400)(-50 3350);
WIRE 16 -1 (-50 3300)(-300 3300);
WIRE 16 -1 (-50 3350)(-50 3300);
WIRE 16 -1 (-50 3250)(-300 3250);
WIRE 16 -1 (-50 3300)(-50 3250);
WIRE 16 -1 (-50 3200)(-300 3200);
WIRE 16 -1 (-50 3250)(-50 3200);
WIRE 16 -1 (-50 3150)(-300 3150);
WIRE 16 -1 (-50 3200)(-50 3150);
WIRE 16 -1 (-50 3100)(-300 3100);
WIRE 16 -1 (-50 3150)(-50 3100);
WIRE 16 -1 (-50 3050)(-300 3050);
WIRE 16 -1 (-50 3100)(-50 3050);
WIRE 16 -1 (-50 3000)(-300 3000);
WIRE 16 -1 (-50 3050)(-50 3000);
WIRE 16 -1 (-300 2950)(-50 2950);
WIRE 16 -1 (-50 3000)(-50 2950);
WIRE 16 -1 (-300 2900)(-50 2900);
WIRE 16 -1 (-50 2950)(-50 2900);
WIRE 16 -1 (-300 2850)(-50 2850);
WIRE 16 -1 (-50 2900)(-50 2850);
WIRE 16 -1 (-300 2800)(-50 2800);
WIRE 16 -1 (-50 2850)(-50 2800);
WIRE 16 -1 (-300 2750)(-50 2750);
WIRE 16 -1 (-50 2800)(-50 2750);
WIRE 16 -1 (-300 2700)(-50 2700);
WIRE 16 -1 (-50 2750)(-50 2700);
WIRE 16 -1 (-300 2650)(-50 2650);
WIRE 16 -1 (-50 2700)(-50 2650);
WIRE 16 -1 (-300 2600)(-50 2600);
WIRE 16 -1 (-50 2600)(-50 2650);
WIRE 16 -1 (-300 2550)(-50 2550);
WIRE 16 -1 (-50 2600)(-50 2550);
WIRE 16 -1 (-50 2500)(-300 2500);
WIRE 16 -1 (-50 2550)(-50 2500);
WIRE 16 -1 (-50 2450)(-300 2450);
WIRE 16 -1 (-50 2500)(-50 2450);
WIRE 16 -1 (-50 2400)(-300 2400);
WIRE 16 -1 (-50 2450)(-50 2400);
WIRE 16 -1 (-50 2350)(-300 2350);
WIRE 16 -1 (-50 2400)(-50 2350);
WIRE 16 -1 (-300 2300)(-50 2300);
WIRE 16 -1 (-50 2300)(-50 2350);
WIRE 16 -1 (-50 2250)(-300 2250);
WIRE 16 -1 (-50 2250)(-50 2300);
WIRE 16 -1 (-50 2200)(-300 2200);
WIRE 16 -1 (-50 2250)(-50 2200);
WIRE 16 -1 (-50 2150)(-300 2150);
WIRE 16 -1 (-50 2200)(-50 2150);
WIRE 16 -1 (-300 -250)(-50 -250);
WIRE 16 -1 (-300 -200)(-50 -200);
WIRE 16 -1 (-50 -250)(-50 -200);
WIRE 16 -1 (-50 2100)(-300 2100);
WIRE 16 -1 (-50 2150)(-50 2100);
WIRE 16 -1 (-50 2050)(-300 2050);
WIRE 16 -1 (-50 2100)(-50 2050);
WIRE 16 -1 (-300 -150)(-50 -150);
WIRE 16 -1 (-50 -150)(-50 -200);
WIRE 16 -1 (-300 -100)(-50 -100);
WIRE 16 -1 (-50 -100)(-50 -150);
WIRE 16 -1 (-50 2000)(-300 2000);
WIRE 16 -1 (-50 2050)(-50 2000);
WIRE 16 -1 (-50 1950)(-300 1950);
WIRE 16 -1 (-50 2000)(-50 1950);
WIRE 16 -1 (-300 -50)(-50 -50);
WIRE 16 -1 (-50 -50)(-50 -100);
WIRE 16 -1 (-300 0)(-50 0);
WIRE 16 -1 (-50 0)(-50 -50);
WIRE 16 -1 (-50 1900)(-300 1900);
WIRE 16 -1 (-50 1950)(-50 1900);
WIRE 16 -1 (-50 1850)(-300 1850);
WIRE 16 -1 (-50 1900)(-50 1850);
WIRE 16 -1 (-300 50)(-50 50);
WIRE 16 -1 (-50 50)(-50 0);
WIRE 16 -1 (-300 100)(-50 100);
WIRE 16 -1 (-50 100)(-50 50);
WIRE 16 -1 (-300 1800)(-50 1800);
WIRE 16 -1 (-50 1850)(-50 1800);
WIRE 16 -1 (-300 1750)(-50 1750);
WIRE 16 -1 (-50 1800)(-50 1750);
WIRE 16 -1 (-50 150)(-300 150);
WIRE 16 -1 (-50 150)(-50 100);
WIRE 16 -1 (-50 200)(-300 200);
WIRE 16 -1 (-50 200)(-50 150);
WIRE 16 -1 (-300 1700)(-50 1700);
WIRE 16 -1 (-50 1750)(-50 1700);
WIRE 16 -1 (-300 1650)(-50 1650);
WIRE 16 -1 (-50 1700)(-50 1650);
WIRE 16 -1 (-50 250)(-300 250);
WIRE 16 -1 (-50 250)(-50 200);
WIRE 16 -1 (-300 300)(-50 300);
WIRE 16 -1 (-50 250)(-50 300);
WIRE 16 -1 (-300 1600)(-50 1600);
WIRE 16 -1 (-50 1650)(-50 1600);
WIRE 16 -1 (-300 1550)(-50 1550);
WIRE 16 -1 (-50 1600)(-50 1550);
WIRE 16 -1 (-50 350)(-300 350);
WIRE 16 -1 (-50 300)(-50 350);
WIRE 16 -1 (-50 400)(-300 400);
WIRE 16 -1 (-50 400)(-50 350);
WIRE 16 -1 (-300 1500)(-50 1500);
WIRE 16 -1 (-50 1550)(-50 1500);
WIRE 16 -1 (-300 1450)(-50 1450);
WIRE 16 -1 (-50 1450)(-50 1500);
WIRE 16 -1 (-50 450)(-300 450);
WIRE 16 -1 (-50 450)(-50 400);
WIRE 16 -1 (-50 500)(-300 500);
WIRE 16 -1 (-50 500)(-50 450);
WIRE 16 -1 (-300 1400)(-50 1400);
WIRE 16 -1 (-50 1450)(-50 1400);
WIRE 16 -1 (-50 1350)(-300 1350);
WIRE 16 -1 (-50 1400)(-50 1350);
WIRE 16 -1 (-300 550)(-50 550);
WIRE 16 -1 (-50 550)(-50 500);
WIRE 16 -1 (-300 600)(-50 600);
WIRE 16 -1 (-50 600)(-50 550);
WIRE 16 -1 (-50 1300)(-300 1300);
WIRE 16 -1 (-50 1350)(-50 1300);
WIRE 16 -1 (-50 1250)(-300 1250);
WIRE 16 -1 (-50 1300)(-50 1250);
WIRE 16 -1 (-300 650)(-50 650);
WIRE 16 -1 (-50 600)(-50 650);
WIRE 16 -1 (-300 700)(-50 700);
WIRE 16 -1 (-50 700)(-50 650);
WIRE 16 -1 (-50 1200)(-300 1200);
WIRE 16 -1 (-50 1250)(-50 1200);
WIRE 16 -1 (-300 1150)(-50 1150);
WIRE 16 -1 (-50 1150)(-50 1200);
WIRE 16 -1 (-300 750)(-50 750);
WIRE 16 -1 (-50 750)(-50 700);
WIRE 16 -1 (-300 800)(-50 800);
WIRE 16 -1 (-50 800)(-50 750);
WIRE 16 -1 (-50 1100)(-300 1100);
WIRE 16 -1 (-50 1100)(-50 1150);
WIRE 16 -1 (-50 1050)(-300 1050);
WIRE 16 -1 (-50 1100)(-50 1050);
WIRE 16 -1 (-300 850)(-50 850);
WIRE 16 -1 (-50 850)(-50 800);
WIRE 16 -1 (-300 900)(-50 900);
WIRE 16 -1 (-50 900)(-50 850);
WIRE 16 -1 (-50 1000)(-300 1000);
WIRE 16 -1 (-50 1050)(-50 1000);
WIRE 16 -1 (-50 1000)(-50 950);
WIRE 16 -1 (-50 950)(-50 900);
WIRE 16 -1 (-300 950)(-50 950);
WIRE 16 -1 (3375 3650)(3125 3650);
WIRE 16 -1 (3125 3650)(3125 3600);
WIRE 16 -1 (3375 3600)(3125 3600);
WIRE 16 -1 (3375 3550)(3125 3550);
WIRE 16 -1 (3125 3600)(3125 3550);
WIRE 16 -1 (3125 3550)(3125 3500);
WIRE 16 -1 (3375 3500)(3125 3500);
WIRE 16 -1 (3125 3500)(3125 3450);
WIRE 16 -1 (3375 3450)(3125 3450);
WIRE 16 -1 (3125 3450)(3125 3400);
WIRE 16 -1 (3375 3400)(3125 3400);
WIRE 16 -1 (3125 3400)(3125 3350);
WIRE 16 -1 (3375 3350)(3125 3350);
WIRE 16 -1 (3125 3350)(3125 3300);
WIRE 16 -1 (3375 3300)(3125 3300);
WIRE 16 -1 (3125 3300)(3125 3250);
WIRE 16 -1 (3375 3250)(3125 3250);
WIRE 16 -1 (3125 3250)(3125 3200);
WIRE 16 -1 (3375 3200)(3125 3200);
WIRE 16 -1 (3125 3200)(3125 3150);
WIRE 16 -1 (3375 3150)(3125 3150);
WIRE 16 -1 (3125 3150)(3125 3100);
WIRE 16 -1 (3375 3100)(3125 3100);
WIRE 16 -1 (3375 3050)(3125 3050);
WIRE 16 -1 (3125 3100)(3125 3050);
WIRE 16 -1 (3125 3050)(3125 3000);
WIRE 16 -1 (3375 3000)(3125 3000);
WIRE 16 -1 (3125 3000)(3125 2950);
WIRE 16 -1 (3125 2950)(3375 2950);
WIRE 16 -1 (3125 2950)(3125 2900);
WIRE 16 -1 (3125 2900)(3375 2900);
WIRE 16 -1 (3125 2900)(3125 2850);
WIRE 16 -1 (3125 2850)(3375 2850);
WIRE 16 -1 (3125 2850)(3125 2800);
WIRE 16 -1 (3125 2800)(3375 2800);
WIRE 16 -1 (3125 2800)(3125 2750);
WIRE 16 -1 (3125 2750)(3375 2750);
WIRE 16 -1 (3125 2750)(3125 2700);
WIRE 16 -1 (3125 2700)(3375 2700);
WIRE 16 -1 (3125 2700)(3125 2650);
WIRE 16 -1 (3125 2650)(3375 2650);
WIRE 16 -1 (3125 2650)(3125 2600);
WIRE 16 -1 (3125 2600)(3375 2600);
WIRE 16 -1 (3125 2550)(3375 2550);
WIRE 16 -1 (3125 2600)(3125 2550);
WIRE 16 -1 (3125 2550)(3125 2500);
WIRE 16 -1 (3125 2500)(3375 2500);
WIRE 16 -1 (3125 2500)(3125 2450);
WIRE 16 -1 (3125 2450)(3375 2450);
WIRE 16 -1 (3125 2450)(3125 2400);
WIRE 16 -1 (3125 2400)(3375 2400);
WIRE 16 -1 (3125 2400)(3125 2350);
WIRE 16 -1 (3125 2350)(3375 2350);
WIRE 16 -1 (3125 2350)(3125 2300);
WIRE 16 -1 (3125 2300)(3375 2300);
WIRE 16 -1 (3125 2300)(3125 2250);
WIRE 16 -1 (3125 2250)(3375 2250);
WIRE 16 -1 (3125 2250)(3125 2200);
WIRE 16 -1 (3125 2200)(3375 2200);
WIRE 16 -1 (3125 2200)(3125 2150);
WIRE 16 -1 (3125 2150)(3375 2150);
WIRE 16 -1 (3125 2150)(3125 2100);
WIRE 16 -1 (3125 2100)(3375 2100);
WIRE 16 -1 (3125 2100)(3125 2050);
WIRE 16 -1 (3125 2050)(3375 2050);
WIRE 16 -1 (3125 2000)(3375 2000);
WIRE 16 -1 (3125 2050)(3125 2000);
WIRE 16 -1 (3125 2000)(3125 1950);
WIRE 16 -1 (3125 1950)(3375 1950);
WIRE 16 -1 (3125 1950)(3125 1900);
WIRE 16 -1 (3125 1900)(3375 1900);
WIRE 16 -1 (3125 1900)(3125 1850);
WIRE 16 -1 (3125 1850)(3375 1850);
WIRE 16 -1 (3125 1850)(3125 1800);
WIRE 16 -1 (3125 1800)(3375 1800);
WIRE 16 -1 (3125 1800)(3125 1750);
WIRE 16 -1 (3125 1750)(3375 1750);
WIRE 16 -1 (3125 1750)(3125 1700);
WIRE 16 -1 (3125 1700)(3375 1700);
WIRE 16 -1 (3125 1700)(3125 1650);
WIRE 16 -1 (3125 1650)(3375 1650);
WIRE 16 -1 (3125 1650)(3125 1600);
WIRE 16 -1 (3375 1600)(3125 1600);
WIRE 16 -1 (3125 1600)(3125 1550);
WIRE 16 -1 (3125 1550)(3375 1550);
WIRE 16 -1 (3125 1500)(3375 1500);
WIRE 16 -1 (3125 1550)(3125 1500);
WIRE 16 -1 (3125 1500)(3125 1450);
WIRE 16 -1 (3125 1450)(3375 1450);
WIRE 16 -1 (3125 1450)(3125 1400);
WIRE 16 -1 (3125 1400)(3375 1400);
WIRE 16 -1 (3125 1400)(3125 1350);
WIRE 16 -1 (3125 1350)(3375 1350);
WIRE 16 -1 (3125 1350)(3125 1300);
WIRE 16 -1 (3125 1300)(3375 1300);
WIRE 16 -1 (3125 1300)(3125 1250);
WIRE 16 -1 (3125 1250)(3375 1250);
WIRE 16 -1 (3125 1250)(3125 1200);
WIRE 16 -1 (3125 1200)(3375 1200);
WIRE 16 -1 (3125 1200)(3125 1150);
WIRE 16 -1 (3125 1150)(3375 1150);
WIRE 16 -1 (3125 1150)(3125 1100);
WIRE 16 -1 (3125 1100)(3375 1100);
WIRE 16 -1 (3125 1100)(3125 1050);
WIRE 16 -1 (3125 1050)(3375 1050);
WIRE 16 -1 (3125 1000)(3375 1000);
WIRE 16 -1 (3125 1050)(3125 1000);
WIRE 16 -1 (3125 1000)(3125 950);
WIRE 16 -1 (3125 950)(3375 950);
WIRE 16 -1 (3125 950)(3125 900);
WIRE 16 -1 (3125 900)(3375 900);
WIRE 16 -1 (3125 900)(3125 850);
WIRE 16 -1 (3125 850)(3375 850);
WIRE 16 -1 (3125 850)(3125 800);
WIRE 16 -1 (3125 800)(3375 800);
WIRE 16 -1 (3125 800)(3125 750);
WIRE 16 -1 (3125 750)(3375 750);
WIRE 16 -1 (3125 750)(3125 700);
WIRE 16 -1 (3125 700)(3375 700);
WIRE 16 -1 (3125 700)(3125 650);
WIRE 16 -1 (3125 650)(3375 650);
WIRE 16 -1 (3125 650)(3125 600);
WIRE 16 -1 (3375 600)(3125 600);
WIRE 16 -1 (3125 600)(3125 550);
WIRE 16 -1 (3125 550)(3375 550);
WIRE 16 -1 (3125 500)(3375 500);
WIRE 16 -1 (3125 550)(3125 500);
WIRE 16 -1 (3125 500)(3125 450);
WIRE 16 -1 (3125 450)(3375 450);
WIRE 16 -1 (3125 450)(3125 400);
WIRE 16 -1 (3125 400)(3375 400);
WIRE 16 -1 (3125 400)(3125 350);
WIRE 16 -1 (3125 350)(3375 350);
WIRE 16 -1 (3125 350)(3125 300);
WIRE 16 -1 (3375 300)(3125 300);
WIRE 16 -1 (3125 300)(3125 250);
WIRE 16 -1 (3125 250)(3375 250);
WIRE 16 -1 (3125 250)(3125 200);
WIRE 16 -1 (3125 200)(3375 200);
WIRE 16 -1 (3125 200)(3125 150);
WIRE 16 -1 (3125 150)(3375 150);
WIRE 16 -1 (3125 150)(3125 100);
WIRE 16 -1 (3125 100)(3375 100);
WIRE 16 -1 (3125 100)(3125 50);
WIRE 16 -1 (3125 50)(3375 50);
WIRE 16 -1 (3125 50)(3125 0);
WIRE 16 -1 (3125 0)(3375 0);
WIRE 16 -1 (3375 -50)(3125 -50);
WIRE 16 -1 (3125 0)(3125 -50);
WIRE 16 -1 (3125 -50)(3125 -100);
WIRE 16 -1 (3125 -100)(3375 -100);
WIRE 16 -1 (3125 -100)(3125 -150);
WIRE 16 -1 (3125 -150)(3375 -150);
WIRE 16 -1 (3125 -150)(3125 -200);
WIRE 16 -1 (3125 -200)(3375 -200);
WIRE 16 -1 (3125 -200)(3125 -250);
WIRE 16 -1 (3125 -250)(3375 -250);
WIRE 16 -1 (6025 3650)(5775 3650);
WIRE 16 -1 (6025 3650)(6025 3600);
WIRE 16 -1 (6025 3600)(5775 3600);
WIRE 16 -1 (6025 3550)(5775 3550);
WIRE 16 -1 (6025 3600)(6025 3550);
WIRE 16 -1 (6025 3500)(5775 3500);
WIRE 16 -1 (6025 3550)(6025 3500);
WIRE 16 -1 (5775 3450)(6025 3450);
WIRE 16 -1 (6025 3450)(6025 3500);
WIRE 16 -1 (6025 3400)(5775 3400);
WIRE 16 -1 (6025 3400)(6025 3450);
WIRE 16 -1 (6025 3350)(5775 3350);
WIRE 16 -1 (6025 3400)(6025 3350);
WIRE 16 -1 (6025 3300)(5775 3300);
WIRE 16 -1 (6025 3350)(6025 3300);
WIRE 16 -1 (6025 3250)(5775 3250);
WIRE 16 -1 (6025 3300)(6025 3250);
WIRE 16 -1 (6025 3200)(5775 3200);
WIRE 16 -1 (6025 3250)(6025 3200);
WIRE 16 -1 (6025 3150)(5775 3150);
WIRE 16 -1 (6025 3200)(6025 3150);
WIRE 16 -1 (6025 3100)(5775 3100);
WIRE 16 -1 (6025 3150)(6025 3100);
WIRE 16 -1 (6025 3050)(5775 3050);
WIRE 16 -1 (6025 3100)(6025 3050);
WIRE 16 -1 (6025 3000)(5775 3000);
WIRE 16 -1 (6025 3050)(6025 3000);
WIRE 16 -1 (5775 2950)(6025 2950);
WIRE 16 -1 (6025 3000)(6025 2950);
WIRE 16 -1 (5775 2900)(6025 2900);
WIRE 16 -1 (6025 2950)(6025 2900);
WIRE 16 -1 (5775 2850)(6025 2850);
WIRE 16 -1 (6025 2900)(6025 2850);
WIRE 16 -1 (5775 2800)(6025 2800);
WIRE 16 -1 (6025 2850)(6025 2800);
WIRE 16 -1 (5775 2750)(6025 2750);
WIRE 16 -1 (6025 2800)(6025 2750);
WIRE 16 -1 (5775 2700)(6025 2700);
WIRE 16 -1 (6025 2750)(6025 2700);
WIRE 16 -1 (5775 2650)(6025 2650);
WIRE 16 -1 (6025 2700)(6025 2650);
WIRE 16 -1 (5775 2600)(6025 2600);
WIRE 16 -1 (6025 2600)(6025 2650);
WIRE 16 -1 (5775 2550)(6025 2550);
WIRE 16 -1 (6025 2600)(6025 2550);
WIRE 16 -1 (6025 2500)(5775 2500);
WIRE 16 -1 (6025 2550)(6025 2500);
WIRE 16 -1 (6025 2450)(5775 2450);
WIRE 16 -1 (6025 2500)(6025 2450);
WIRE 16 -1 (6025 2400)(5775 2400);
WIRE 16 -1 (6025 2450)(6025 2400);
WIRE 16 -1 (6025 2350)(5775 2350);
WIRE 16 -1 (6025 2400)(6025 2350);
WIRE 16 -1 (5775 2300)(6025 2300);
WIRE 16 -1 (6025 2300)(6025 2350);
WIRE 16 -1 (6025 2250)(5775 2250);
WIRE 16 -1 (6025 2250)(6025 2300);
WIRE 16 -1 (6025 2200)(5775 2200);
WIRE 16 -1 (6025 2250)(6025 2200);
WIRE 16 -1 (6025 2150)(5775 2150);
WIRE 16 -1 (6025 2200)(6025 2150);
WIRE 16 -1 (6025 2100)(5775 2100);
WIRE 16 -1 (6025 2150)(6025 2100);
WIRE 16 -1 (6025 2050)(5775 2050);
WIRE 16 -1 (6025 2100)(6025 2050);
WIRE 16 -1 (6025 2000)(5775 2000);
WIRE 16 -1 (6025 2050)(6025 2000);
WIRE 16 -1 (6025 1950)(5775 1950);
WIRE 16 -1 (6025 2000)(6025 1950);
WIRE 16 -1 (6025 1900)(5775 1900);
WIRE 16 -1 (6025 1950)(6025 1900);
WIRE 16 -1 (6025 1850)(5775 1850);
WIRE 16 -1 (6025 1900)(6025 1850);
WIRE 16 -1 (5775 1800)(6025 1800);
WIRE 16 -1 (6025 1850)(6025 1800);
WIRE 16 -1 (5775 1750)(6025 1750);
WIRE 16 -1 (6025 1800)(6025 1750);
WIRE 16 -1 (5775 1700)(6025 1700);
WIRE 16 -1 (6025 1750)(6025 1700);
WIRE 16 -1 (5775 1650)(6025 1650);
WIRE 16 -1 (6025 1700)(6025 1650);
WIRE 16 -1 (5775 1600)(6025 1600);
WIRE 16 -1 (6025 1650)(6025 1600);
WIRE 16 -1 (5775 1550)(6025 1550);
WIRE 16 -1 (6025 1600)(6025 1550);
WIRE 16 -1 (5775 1500)(6025 1500);
WIRE 16 -1 (6025 1550)(6025 1500);
WIRE 16 -1 (5775 1450)(6025 1450);
WIRE 16 -1 (6025 1450)(6025 1500);
WIRE 16 -1 (5775 1400)(6025 1400);
WIRE 16 -1 (6025 1450)(6025 1400);
WIRE 16 -1 (6025 1350)(5775 1350);
WIRE 16 -1 (6025 1400)(6025 1350);
WIRE 16 -1 (6025 1300)(5775 1300);
WIRE 16 -1 (6025 1350)(6025 1300);
WIRE 16 -1 (6025 1250)(5775 1250);
WIRE 16 -1 (6025 1300)(6025 1250);
WIRE 16 -1 (6025 1200)(5775 1200);
WIRE 16 -1 (6025 1250)(6025 1200);
WIRE 16 -1 (5775 1150)(6025 1150);
WIRE 16 -1 (6025 1150)(6025 1200);
WIRE 16 -1 (6025 1100)(5775 1100);
WIRE 16 -1 (6025 1100)(6025 1150);
WIRE 16 -1 (6025 1050)(5775 1050);
WIRE 16 -1 (6025 1100)(6025 1050);
WIRE 16 -1 (6025 1000)(5775 1000);
WIRE 16 -1 (6025 1050)(6025 1000);
WIRE 16 -1 (5775 950)(6025 950);
WIRE 16 -1 (6025 1000)(6025 950);
WIRE 16 -1 (5775 900)(6025 900);
WIRE 16 -1 (6025 950)(6025 900);
WIRE 16 -1 (5775 850)(6025 850);
WIRE 16 -1 (6025 900)(6025 850);
WIRE 16 -1 (5775 800)(6025 800);
WIRE 16 -1 (6025 850)(6025 800);
WIRE 16 -1 (5775 750)(6025 750);
WIRE 16 -1 (6025 800)(6025 750);
WIRE 16 -1 (5775 700)(6025 700);
WIRE 16 -1 (6025 750)(6025 700);
WIRE 16 -1 (5775 650)(6025 650);
WIRE 16 -1 (6025 700)(6025 650);
WIRE 16 -1 (5775 600)(6025 600);
WIRE 16 -1 (6025 600)(6025 650);
WIRE 16 -1 (5775 550)(6025 550);
WIRE 16 -1 (6025 600)(6025 550);
WIRE 16 -1 (6025 500)(5775 500);
WIRE 16 -1 (6025 550)(6025 500);
WIRE 16 -1 (6025 450)(5775 450);
WIRE 16 -1 (6025 500)(6025 450);
WIRE 16 -1 (6025 400)(5775 400);
WIRE 16 -1 (6025 450)(6025 400);
WIRE 16 -1 (6025 350)(5775 350);
WIRE 16 -1 (6025 400)(6025 350);
WIRE 16 -1 (5775 300)(6025 300);
WIRE 16 -1 (6025 300)(6025 350);
WIRE 16 -1 (6025 250)(5775 250);
WIRE 16 -1 (6025 250)(6025 300);
WIRE 16 -1 (6025 200)(5775 200);
WIRE 16 -1 (6025 250)(6025 200);
WIRE 16 -1 (6025 150)(5775 150);
WIRE 16 -1 (6025 200)(6025 150);
WIRE 16 -1 (5775 100)(6025 100);
WIRE 16 -1 (6025 150)(6025 100);
WIRE 16 -1 (5775 50)(6025 50);
WIRE 16 -1 (6025 100)(6025 50);
WIRE 16 -1 (6025 50)(6025 0);
WIRE 16 -1 (5775 0)(6025 0);
WIRE 16 -1 (5775 -50)(6025 -50);
WIRE 16 -1 (6025 0)(6025 -50);
WIRE 16 -1 (5775 -100)(6025 -100);
WIRE 16 -1 (6025 -50)(6025 -100);
WIRE 16 -1 (5775 -150)(6025 -150);
WIRE 16 -1 (6025 -100)(6025 -150);
WIRE 16 -1 (5775 -200)(6025 -200);
WIRE 16 -1 (6025 -150)(6025 -200);
WIRE 16 -1 (6025 -250)(6025 -200);
WIRE 16 -1 (5775 -250)(6025 -250);
WIRE 16 -1 (350 3650)(100 3650);
WIRE 16 -1 (100 3650)(100 3600);
WIRE 16 -1 (350 3600)(100 3600);
WIRE 16 -1 (350 3550)(100 3550);
WIRE 16 -1 (100 3600)(100 3550);
WIRE 16 -1 (100 3550)(100 3500);
WIRE 16 -1 (350 3500)(100 3500);
WIRE 16 -1 (100 3500)(100 3450);
WIRE 16 -1 (350 3450)(100 3450);
WIRE 16 -1 (100 3450)(100 3400);
WIRE 16 -1 (350 3400)(100 3400);
WIRE 16 -1 (100 3400)(100 3350);
WIRE 16 -1 (350 3350)(100 3350);
WIRE 16 -1 (100 3350)(100 3300);
WIRE 16 -1 (350 3300)(100 3300);
WIRE 16 -1 (100 3300)(100 3250);
WIRE 16 -1 (350 3250)(100 3250);
WIRE 16 -1 (100 3250)(100 3200);
WIRE 16 -1 (350 3200)(100 3200);
WIRE 16 -1 (100 3200)(100 3150);
WIRE 16 -1 (350 3150)(100 3150);
WIRE 16 -1 (100 3150)(100 3100);
WIRE 16 -1 (350 3100)(100 3100);
WIRE 16 -1 (350 3050)(100 3050);
WIRE 16 -1 (100 3100)(100 3050);
WIRE 16 -1 (100 3050)(100 3000);
WIRE 16 -1 (350 3000)(100 3000);
WIRE 16 -1 (100 3000)(100 2950);
WIRE 16 -1 (100 2950)(350 2950);
WIRE 16 -1 (100 2950)(100 2900);
WIRE 16 -1 (100 2900)(350 2900);
WIRE 16 -1 (100 2900)(100 2850);
WIRE 16 -1 (100 2850)(350 2850);
WIRE 16 -1 (100 2850)(100 2800);
WIRE 16 -1 (100 2800)(350 2800);
WIRE 16 -1 (100 2800)(100 2750);
WIRE 16 -1 (100 2750)(350 2750);
WIRE 16 -1 (100 2750)(100 2700);
WIRE 16 -1 (100 2700)(350 2700);
WIRE 16 -1 (100 2700)(100 2650);
WIRE 16 -1 (100 2650)(350 2650);
WIRE 16 -1 (100 2650)(100 2600);
WIRE 16 -1 (100 2600)(350 2600);
WIRE 16 -1 (100 2550)(350 2550);
WIRE 16 -1 (100 2600)(100 2550);
WIRE 16 -1 (100 2550)(100 2500);
WIRE 16 -1 (100 2500)(350 2500);
WIRE 16 -1 (100 2500)(100 2450);
WIRE 16 -1 (100 2450)(350 2450);
WIRE 16 -1 (100 2450)(100 2400);
WIRE 16 -1 (100 2400)(350 2400);
WIRE 16 -1 (100 2400)(100 2350);
WIRE 16 -1 (100 2350)(350 2350);
WIRE 16 -1 (100 2350)(100 2300);
WIRE 16 -1 (100 2300)(350 2300);
WIRE 16 -1 (100 2300)(100 2250);
WIRE 16 -1 (100 2250)(350 2250);
WIRE 16 -1 (100 2250)(100 2200);
WIRE 16 -1 (100 2200)(350 2200);
WIRE 16 -1 (100 2200)(100 2150);
WIRE 16 -1 (100 2150)(350 2150);
WIRE 16 -1 (100 2150)(100 2100);
WIRE 16 -1 (100 2100)(350 2100);
WIRE 16 -1 (100 2100)(100 2050);
WIRE 16 -1 (100 2050)(350 2050);
WIRE 16 -1 (100 2000)(350 2000);
WIRE 16 -1 (100 2050)(100 2000);
WIRE 16 -1 (100 2000)(100 1950);
WIRE 16 -1 (100 1950)(350 1950);
WIRE 16 -1 (100 1950)(100 1900);
WIRE 16 -1 (100 1900)(350 1900);
WIRE 16 -1 (100 1900)(100 1850);
WIRE 16 -1 (100 1850)(350 1850);
WIRE 16 -1 (100 1850)(100 1800);
WIRE 16 -1 (100 1800)(350 1800);
WIRE 16 -1 (100 1800)(100 1750);
WIRE 16 -1 (100 1750)(350 1750);
WIRE 16 -1 (100 1750)(100 1700);
WIRE 16 -1 (100 1700)(350 1700);
WIRE 16 -1 (100 1700)(100 1650);
WIRE 16 -1 (100 1650)(350 1650);
WIRE 16 -1 (100 1650)(100 1600);
WIRE 16 -1 (350 1600)(100 1600);
WIRE 16 -1 (100 1600)(100 1550);
WIRE 16 -1 (100 1550)(350 1550);
WIRE 16 -1 (100 1500)(350 1500);
WIRE 16 -1 (100 1550)(100 1500);
WIRE 16 -1 (100 1500)(100 1450);
WIRE 16 -1 (100 1450)(350 1450);
WIRE 16 -1 (100 1450)(100 1400);
WIRE 16 -1 (100 1400)(350 1400);
WIRE 16 -1 (100 1400)(100 1350);
WIRE 16 -1 (100 1350)(350 1350);
WIRE 16 -1 (100 1350)(100 1300);
WIRE 16 -1 (100 1300)(350 1300);
WIRE 16 -1 (100 1300)(100 1250);
WIRE 16 -1 (100 1250)(350 1250);
WIRE 16 -1 (100 1250)(100 1200);
WIRE 16 -1 (100 1200)(350 1200);
WIRE 16 -1 (100 1200)(100 1150);
WIRE 16 -1 (100 1150)(350 1150);
WIRE 16 -1 (100 1150)(100 1100);
WIRE 16 -1 (100 1100)(350 1100);
WIRE 16 -1 (100 1100)(100 1050);
WIRE 16 -1 (100 1050)(350 1050);
WIRE 16 -1 (100 1000)(350 1000);
WIRE 16 -1 (100 1050)(100 1000);
WIRE 16 -1 (100 1000)(100 950);
WIRE 16 -1 (100 950)(350 950);
WIRE 16 -1 (100 950)(100 900);
WIRE 16 -1 (100 900)(350 900);
WIRE 16 -1 (100 900)(100 850);
WIRE 16 -1 (100 850)(350 850);
WIRE 16 -1 (100 850)(100 800);
WIRE 16 -1 (100 800)(350 800);
WIRE 16 -1 (100 800)(100 750);
WIRE 16 -1 (100 750)(350 750);
WIRE 16 -1 (100 750)(100 700);
WIRE 16 -1 (100 700)(350 700);
WIRE 16 -1 (100 700)(100 650);
WIRE 16 -1 (100 650)(350 650);
WIRE 16 -1 (100 650)(100 600);
WIRE 16 -1 (350 600)(100 600);
WIRE 16 -1 (100 600)(100 550);
WIRE 16 -1 (100 550)(350 550);
WIRE 16 -1 (100 500)(350 500);
WIRE 16 -1 (100 550)(100 500);
WIRE 16 -1 (100 500)(100 450);
WIRE 16 -1 (100 450)(350 450);
WIRE 16 -1 (100 450)(100 400);
WIRE 16 -1 (100 400)(350 400);
WIRE 16 -1 (100 400)(100 350);
WIRE 16 -1 (100 350)(350 350);
WIRE 16 -1 (100 350)(100 300);
WIRE 16 -1 (350 300)(100 300);
WIRE 16 -1 (100 300)(100 250);
WIRE 16 -1 (100 250)(350 250);
WIRE 16 -1 (100 250)(100 200);
WIRE 16 -1 (100 200)(350 200);
WIRE 16 -1 (100 200)(100 150);
WIRE 16 -1 (100 150)(350 150);
WIRE 16 -1 (100 150)(100 100);
WIRE 16 -1 (100 100)(350 100);
WIRE 16 -1 (100 100)(100 50);
WIRE 16 -1 (100 50)(350 50);
WIRE 16 -1 (100 50)(100 0);
WIRE 16 -1 (100 0)(350 0);
WIRE 16 -1 (350 -50)(100 -50);
WIRE 16 -1 (100 0)(100 -50);
WIRE 16 -1 (100 -50)(100 -100);
WIRE 16 -1 (100 -100)(350 -100);
WIRE 16 -1 (100 -100)(100 -150);
WIRE 16 -1 (100 -150)(350 -150);
WIRE 16 -1 (100 -150)(100 -200);
WIRE 16 -1 (100 -200)(350 -200);
WIRE 16 -1 (100 -200)(100 -250);
WIRE 16 -1 (100 -250)(350 -250);
WIRE 16 -1 (3000 3650)(2750 3650);
WIRE 16 -1 (3000 3600)(2750 3600);
WIRE 16 -1 (3000 3650)(3000 3600);
WIRE 16 -1 (3000 3550)(2750 3550);
WIRE 16 -1 (3000 3600)(3000 3550);
WIRE 16 -1 (3000 3500)(2750 3500);
WIRE 16 -1 (3000 3550)(3000 3500);
WIRE 16 -1 (2750 3450)(3000 3450);
WIRE 16 -1 (3000 3450)(3000 3500);
WIRE 16 -1 (3000 3400)(2750 3400);
WIRE 16 -1 (3000 3400)(3000 3450);
WIRE 16 -1 (3000 3350)(2750 3350);
WIRE 16 -1 (3000 3400)(3000 3350);
WIRE 16 -1 (3000 3300)(2750 3300);
WIRE 16 -1 (3000 3350)(3000 3300);
WIRE 16 -1 (3000 3250)(2750 3250);
WIRE 16 -1 (3000 3300)(3000 3250);
WIRE 16 -1 (3000 3200)(2750 3200);
WIRE 16 -1 (3000 3250)(3000 3200);
WIRE 16 -1 (3000 3150)(2750 3150);
WIRE 16 -1 (3000 3200)(3000 3150);
WIRE 16 -1 (3000 3100)(2750 3100);
WIRE 16 -1 (3000 3150)(3000 3100);
WIRE 16 -1 (3000 3050)(2750 3050);
WIRE 16 -1 (3000 3100)(3000 3050);
WIRE 16 -1 (3000 3000)(2750 3000);
WIRE 16 -1 (3000 3050)(3000 3000);
WIRE 16 -1 (2750 2950)(3000 2950);
WIRE 16 -1 (3000 3000)(3000 2950);
WIRE 16 -1 (2750 2900)(3000 2900);
WIRE 16 -1 (3000 2950)(3000 2900);
WIRE 16 -1 (2750 2850)(3000 2850);
WIRE 16 -1 (3000 2900)(3000 2850);
WIRE 16 -1 (2750 2800)(3000 2800);
WIRE 16 -1 (3000 2850)(3000 2800);
WIRE 16 -1 (2750 2750)(3000 2750);
WIRE 16 -1 (3000 2800)(3000 2750);
WIRE 16 -1 (2750 2700)(3000 2700);
WIRE 16 -1 (3000 2750)(3000 2700);
WIRE 16 -1 (2750 2650)(3000 2650);
WIRE 16 -1 (3000 2700)(3000 2650);
WIRE 16 -1 (2750 2600)(3000 2600);
WIRE 16 -1 (3000 2600)(3000 2650);
WIRE 16 -1 (2750 2550)(3000 2550);
WIRE 16 -1 (3000 2600)(3000 2550);
WIRE 16 -1 (3000 2500)(2750 2500);
WIRE 16 -1 (3000 2550)(3000 2500);
WIRE 16 -1 (3000 2450)(2750 2450);
WIRE 16 -1 (3000 2500)(3000 2450);
WIRE 16 -1 (3000 2400)(2750 2400);
WIRE 16 -1 (3000 2450)(3000 2400);
WIRE 16 -1 (3000 2350)(2750 2350);
WIRE 16 -1 (3000 2400)(3000 2350);
WIRE 16 -1 (2750 2300)(3000 2300);
WIRE 16 -1 (3000 2300)(3000 2350);
WIRE 16 -1 (3000 2250)(2750 2250);
WIRE 16 -1 (3000 2250)(3000 2300);
WIRE 16 -1 (3000 2200)(2750 2200);
WIRE 16 -1 (3000 2250)(3000 2200);
WIRE 16 -1 (3000 2150)(2750 2150);
WIRE 16 -1 (3000 2200)(3000 2150);
WIRE 16 -1 (3000 2100)(2750 2100);
WIRE 16 -1 (3000 2150)(3000 2100);
WIRE 16 -1 (3000 2050)(2750 2050);
WIRE 16 -1 (3000 2100)(3000 2050);
WIRE 16 -1 (3000 2000)(2750 2000);
WIRE 16 -1 (3000 2050)(3000 2000);
WIRE 16 -1 (3000 1950)(2750 1950);
WIRE 16 -1 (3000 2000)(3000 1950);
WIRE 16 -1 (3000 1900)(2750 1900);
WIRE 16 -1 (3000 1950)(3000 1900);
WIRE 16 -1 (3000 1850)(2750 1850);
WIRE 16 -1 (3000 1900)(3000 1850);
WIRE 16 -1 (2750 1800)(3000 1800);
WIRE 16 -1 (3000 1850)(3000 1800);
WIRE 16 -1 (2750 1750)(3000 1750);
WIRE 16 -1 (3000 1800)(3000 1750);
WIRE 16 -1 (2750 1700)(3000 1700);
WIRE 16 -1 (3000 1750)(3000 1700);
WIRE 16 -1 (2750 1650)(3000 1650);
WIRE 16 -1 (3000 1700)(3000 1650);
WIRE 16 -1 (2750 1600)(3000 1600);
WIRE 16 -1 (3000 1650)(3000 1600);
WIRE 16 -1 (2750 1550)(3000 1550);
WIRE 16 -1 (3000 1600)(3000 1550);
WIRE 16 -1 (2750 1500)(3000 1500);
WIRE 16 -1 (3000 1550)(3000 1500);
WIRE 16 -1 (2750 1450)(3000 1450);
WIRE 16 -1 (3000 1450)(3000 1500);
WIRE 16 -1 (2750 1400)(3000 1400);
WIRE 16 -1 (3000 1450)(3000 1400);
WIRE 16 -1 (3000 1350)(2750 1350);
WIRE 16 -1 (3000 1400)(3000 1350);
WIRE 16 -1 (3000 1300)(2750 1300);
WIRE 16 -1 (3000 1350)(3000 1300);
WIRE 16 -1 (3000 1250)(2750 1250);
WIRE 16 -1 (3000 1300)(3000 1250);
WIRE 16 -1 (3000 1200)(2750 1200);
WIRE 16 -1 (3000 1250)(3000 1200);
WIRE 16 -1 (2750 1150)(3000 1150);
WIRE 16 -1 (3000 1150)(3000 1200);
WIRE 16 -1 (3000 1100)(2750 1100);
WIRE 16 -1 (3000 1100)(3000 1150);
WIRE 16 -1 (3000 1050)(2750 1050);
WIRE 16 -1 (3000 1100)(3000 1050);
WIRE 16 -1 (3000 1000)(2750 1000);
WIRE 16 -1 (3000 1050)(3000 1000);
WIRE 16 -1 (2750 950)(3000 950);
WIRE 16 -1 (3000 1000)(3000 950);
WIRE 16 -1 (2750 900)(3000 900);
WIRE 16 -1 (3000 950)(3000 900);
WIRE 16 -1 (2750 850)(3000 850);
WIRE 16 -1 (3000 900)(3000 850);
WIRE 16 -1 (2750 800)(3000 800);
WIRE 16 -1 (3000 850)(3000 800);
WIRE 16 -1 (2750 750)(3000 750);
WIRE 16 -1 (3000 800)(3000 750);
WIRE 16 -1 (2750 700)(3000 700);
WIRE 16 -1 (3000 750)(3000 700);
WIRE 16 -1 (2750 650)(3000 650);
WIRE 16 -1 (3000 700)(3000 650);
WIRE 16 -1 (2750 600)(3000 600);
WIRE 16 -1 (3000 600)(3000 650);
WIRE 16 -1 (2750 550)(3000 550);
WIRE 16 -1 (3000 600)(3000 550);
WIRE 16 -1 (3000 500)(2750 500);
WIRE 16 -1 (3000 550)(3000 500);
WIRE 16 -1 (3000 450)(2750 450);
WIRE 16 -1 (3000 500)(3000 450);
WIRE 16 -1 (3000 400)(2750 400);
WIRE 16 -1 (3000 450)(3000 400);
WIRE 16 -1 (3000 350)(2750 350);
WIRE 16 -1 (3000 400)(3000 350);
WIRE 16 -1 (2750 300)(3000 300);
WIRE 16 -1 (3000 300)(3000 350);
WIRE 16 -1 (3000 250)(2750 250);
WIRE 16 -1 (3000 250)(3000 300);
WIRE 16 -1 (3000 200)(2750 200);
WIRE 16 -1 (3000 250)(3000 200);
WIRE 16 -1 (3000 150)(2750 150);
WIRE 16 -1 (3000 200)(3000 150);
WIRE 16 -1 (2750 100)(3000 100);
WIRE 16 -1 (3000 150)(3000 100);
WIRE 16 -1 (2750 50)(3000 50);
WIRE 16 -1 (3000 100)(3000 50);
WIRE 16 -1 (3000 50)(3000 0);
WIRE 16 -1 (2750 0)(3000 0);
WIRE 16 -1 (2750 -50)(3000 -50);
WIRE 16 -1 (3000 0)(3000 -50);
WIRE 16 -1 (2750 -100)(3000 -100);
WIRE 16 -1 (3000 -50)(3000 -100);
WIRE 16 -1 (2750 -150)(3000 -150);
WIRE 16 -1 (3000 -100)(3000 -150);
WIRE 16 -1 (2750 -200)(3000 -200);
WIRE 16 -1 (3000 -150)(3000 -200);
WIRE 16 -1 (3000 -250)(3000 -200);
WIRE 16 -1 (2750 -250)(3000 -250);
WIRE 16 -1 (-2700 3650)(-2950 3650);
WIRE 16 -1 (-2950 3650)(-2950 3600);
WIRE 16 -1 (-2700 3600)(-2950 3600);
WIRE 16 -1 (-2700 3550)(-2950 3550);
WIRE 16 -1 (-2950 3600)(-2950 3550);
WIRE 16 -1 (-2950 3550)(-2950 3500);
WIRE 16 -1 (-2700 3500)(-2950 3500);
WIRE 16 -1 (-2950 3500)(-2950 3450);
WIRE 16 -1 (-2700 3450)(-2950 3450);
WIRE 16 -1 (-2950 3450)(-2950 3400);
WIRE 16 -1 (-2700 3400)(-2950 3400);
WIRE 16 -1 (-2950 3400)(-2950 3350);
WIRE 16 -1 (-2700 3350)(-2950 3350);
WIRE 16 -1 (-2950 3350)(-2950 3300);
WIRE 16 -1 (-2700 3300)(-2950 3300);
WIRE 16 -1 (-2950 3300)(-2950 3250);
WIRE 16 -1 (-2700 3250)(-2950 3250);
WIRE 16 -1 (-2950 3250)(-2950 3200);
WIRE 16 -1 (-2700 3200)(-2950 3200);
WIRE 16 -1 (-2950 3200)(-2950 3150);
WIRE 16 -1 (-2700 3150)(-2950 3150);
WIRE 16 -1 (-2950 3150)(-2950 3100);
WIRE 16 -1 (-2700 3100)(-2950 3100);
WIRE 16 -1 (-2700 3050)(-2950 3050);
WIRE 16 -1 (-2950 3100)(-2950 3050);
WIRE 16 -1 (-2950 3050)(-2950 3000);
WIRE 16 -1 (-2700 3000)(-2950 3000);
WIRE 16 -1 (-2950 3000)(-2950 2950);
WIRE 16 -1 (-2950 2950)(-2700 2950);
WIRE 16 -1 (-2950 2950)(-2950 2900);
WIRE 16 -1 (-2950 2900)(-2700 2900);
WIRE 16 -1 (-2950 2900)(-2950 2850);
WIRE 16 -1 (-2950 2850)(-2700 2850);
WIRE 16 -1 (-2950 2850)(-2950 2800);
WIRE 16 -1 (-2950 2800)(-2700 2800);
WIRE 16 -1 (-2950 2800)(-2950 2750);
WIRE 16 -1 (-2950 2750)(-2700 2750);
WIRE 16 -1 (-2950 2750)(-2950 2700);
WIRE 16 -1 (-2950 2700)(-2700 2700);
WIRE 16 -1 (-2950 2700)(-2950 2650);
WIRE 16 -1 (-2950 2650)(-2700 2650);
WIRE 16 -1 (-2950 2650)(-2950 2600);
WIRE 16 -1 (-2950 2600)(-2700 2600);
WIRE 16 -1 (-2950 2550)(-2700 2550);
WIRE 16 -1 (-2950 2600)(-2950 2550);
WIRE 16 -1 (-2950 2550)(-2950 2500);
WIRE 16 -1 (-2950 2500)(-2700 2500);
WIRE 16 -1 (-2950 2500)(-2950 2450);
WIRE 16 -1 (-2950 2450)(-2700 2450);
WIRE 16 -1 (-2950 2450)(-2950 2400);
WIRE 16 -1 (-2950 2400)(-2700 2400);
WIRE 16 -1 (-2950 2400)(-2950 2350);
WIRE 16 -1 (-2950 2350)(-2700 2350);
WIRE 16 -1 (-2950 2350)(-2950 2300);
WIRE 16 -1 (-2950 2300)(-2700 2300);
WIRE 16 -1 (-2950 2300)(-2950 2250);
WIRE 16 -1 (-2950 2250)(-2700 2250);
WIRE 16 -1 (-2950 2250)(-2950 2200);
WIRE 16 -1 (-2950 2200)(-2700 2200);
WIRE 16 -1 (-2950 2200)(-2950 2150);
WIRE 16 -1 (-2950 2150)(-2700 2150);
WIRE 16 -1 (-2950 2150)(-2950 2100);
WIRE 16 -1 (-2950 2100)(-2700 2100);
WIRE 16 -1 (-2950 2100)(-2950 2050);
WIRE 16 -1 (-2950 2050)(-2700 2050);
WIRE 16 -1 (-2950 2000)(-2700 2000);
WIRE 16 -1 (-2950 2050)(-2950 2000);
WIRE 16 -1 (-2950 2000)(-2950 1950);
WIRE 16 -1 (-2950 1950)(-2700 1950);
WIRE 16 -1 (-2950 1950)(-2950 1900);
WIRE 16 -1 (-2950 1900)(-2700 1900);
WIRE 16 -1 (-2950 1900)(-2950 1850);
WIRE 16 -1 (-2950 1850)(-2700 1850);
WIRE 16 -1 (-2950 1850)(-2950 1800);
WIRE 16 -1 (-2950 1800)(-2700 1800);
WIRE 16 -1 (-2950 1800)(-2950 1750);
WIRE 16 -1 (-2950 1750)(-2700 1750);
WIRE 16 -1 (-2950 1750)(-2950 1700);
WIRE 16 -1 (-2950 1700)(-2700 1700);
WIRE 16 -1 (-2950 1700)(-2950 1650);
WIRE 16 -1 (-2950 1650)(-2700 1650);
WIRE 16 -1 (-2950 1650)(-2950 1600);
WIRE 16 -1 (-2700 1600)(-2950 1600);
WIRE 16 -1 (-2950 1600)(-2950 1550);
WIRE 16 -1 (-2950 1550)(-2700 1550);
WIRE 16 -1 (-2950 1500)(-2700 1500);
WIRE 16 -1 (-2950 1550)(-2950 1500);
WIRE 16 -1 (-2950 1500)(-2950 1450);
WIRE 16 -1 (-2950 1450)(-2700 1450);
WIRE 16 -1 (-2950 1450)(-2950 1400);
WIRE 16 -1 (-2950 1400)(-2700 1400);
WIRE 16 -1 (-2950 1400)(-2950 1350);
WIRE 16 -1 (-2950 1350)(-2700 1350);
WIRE 16 -1 (-2950 1350)(-2950 1300);
WIRE 16 -1 (-2950 1300)(-2700 1300);
WIRE 16 -1 (-2950 1300)(-2950 1250);
WIRE 16 -1 (-2950 1250)(-2700 1250);
WIRE 16 -1 (-2950 1250)(-2950 1200);
WIRE 16 -1 (-2950 1200)(-2700 1200);
WIRE 16 -1 (-2950 1200)(-2950 1150);
WIRE 16 -1 (-2950 1150)(-2700 1150);
WIRE 16 -1 (-2950 1150)(-2950 1100);
WIRE 16 -1 (-2950 1100)(-2700 1100);
WIRE 16 -1 (-2950 1100)(-2950 1050);
WIRE 16 -1 (-2950 1050)(-2700 1050);
WIRE 16 -1 (-2950 1000)(-2700 1000);
WIRE 16 -1 (-2950 1050)(-2950 1000);
WIRE 16 -1 (-2950 1000)(-2950 950);
WIRE 16 -1 (-2950 950)(-2700 950);
WIRE 16 -1 (-2950 950)(-2950 900);
WIRE 16 -1 (-2950 900)(-2700 900);
WIRE 16 -1 (-2950 900)(-2950 850);
WIRE 16 -1 (-2950 850)(-2700 850);
WIRE 16 -1 (-2950 850)(-2950 800);
WIRE 16 -1 (-2950 800)(-2700 800);
WIRE 16 -1 (-2950 800)(-2950 750);
WIRE 16 -1 (-2950 750)(-2700 750);
WIRE 16 -1 (-2950 750)(-2950 700);
WIRE 16 -1 (-2950 700)(-2700 700);
WIRE 16 -1 (-2950 700)(-2950 650);
WIRE 16 -1 (-2950 650)(-2700 650);
WIRE 16 -1 (-2950 650)(-2950 600);
WIRE 16 -1 (-2700 600)(-2950 600);
WIRE 16 -1 (-2950 600)(-2950 550);
WIRE 16 -1 (-2950 550)(-2700 550);
WIRE 16 -1 (-2950 500)(-2700 500);
WIRE 16 -1 (-2950 550)(-2950 500);
WIRE 16 -1 (-2950 500)(-2950 450);
WIRE 16 -1 (-2950 450)(-2700 450);
WIRE 16 -1 (-2950 450)(-2950 400);
WIRE 16 -1 (-2950 400)(-2700 400);
WIRE 16 -1 (-2950 400)(-2950 350);
WIRE 16 -1 (-2950 350)(-2700 350);
WIRE 16 -1 (-2950 350)(-2950 300);
WIRE 16 -1 (-2700 300)(-2950 300);
WIRE 16 -1 (-2950 300)(-2950 250);
WIRE 16 -1 (-2950 250)(-2700 250);
WIRE 16 -1 (-2950 250)(-2950 200);
WIRE 16 -1 (-2950 200)(-2700 200);
WIRE 16 -1 (-2950 200)(-2950 150);
WIRE 16 -1 (-2950 150)(-2700 150);
WIRE 16 -1 (-2950 150)(-2950 100);
WIRE 16 -1 (-2950 100)(-2700 100);
WIRE 16 -1 (-2950 100)(-2950 50);
WIRE 16 -1 (-2950 50)(-2700 50);
WIRE 16 -1 (-2950 50)(-2950 0);
WIRE 16 -1 (-2950 0)(-2700 0);
WIRE 16 -1 (-2700 -50)(-2950 -50);
WIRE 16 -1 (-2950 0)(-2950 -50);
WIRE 16 -1 (-2950 -50)(-2950 -100);
WIRE 16 -1 (-2950 -100)(-2700 -100);
WIRE 16 -1 (-2950 -100)(-2950 -150);
WIRE 16 -1 (-2950 -150)(-2700 -150);
WIRE 16 -1 (-2950 -150)(-2950 -200);
WIRE 16 -1 (-2950 -200)(-2700 -200);
WIRE 16 -1 (-2950 -200)(-2950 -250);
WIRE 16 -1 (-2950 -250)(-2700 -250);
DOT 1 (100 3100);
DOT 1 (-50 2950);
DOT 1 (6025 3600);
DOT 1 (6025 3550);
DOT 1 (6025 3350);
DOT 1 (6025 3400);
DOT 1 (6025 3450);
DOT 1 (6025 3500);
DOT 1 (6025 3300);
DOT 1 (6025 3200);
DOT 1 (6025 3100);
DOT 1 (6025 3150);
DOT 1 (6025 3250);
DOT 1 (6025 3000);
DOT 1 (6025 2850);
DOT 1 (6025 2900);
DOT 1 (6025 3050);
DOT 1 (6025 2950);
DOT 1 (6025 2800);
DOT 1 (6025 2650);
DOT 1 (6025 2600);
DOT 1 (6025 2700);
DOT 1 (6025 2750);
DOT 1 (6025 2550);
DOT 1 (6025 2350);
DOT 1 (6025 2400);
DOT 1 (6025 2450);
DOT 1 (6025 2500);
DOT 1 (6025 2300);
DOT 1 (6025 2250);
DOT 1 (6025 2100);
DOT 1 (6025 2150);
DOT 1 (6025 2200);
DOT 1 (6025 2050);
DOT 1 (6025 2000);
DOT 1 (6025 1850);
DOT 1 (6025 1900);
DOT 1 (6025 1950);
DOT 1 (6025 1800);
DOT 1 (6025 1750);
DOT 1 (6025 1550);
DOT 1 (6025 1600);
DOT 1 (6025 1650);
DOT 1 (6025 1700);
DOT 1 (6025 1500);
DOT 1 (6025 1300);
DOT 1 (6025 1350);
DOT 1 (6025 1400);
DOT 1 (6025 1450);
DOT 1 (6025 1250);
DOT 1 (6025 1100);
DOT 1 (6025 1050);
DOT 1 (6025 1150);
DOT 1 (6025 1200);
DOT 1 (6025 1000);
DOT 1 (6025 850);
DOT 1 (6025 800);
DOT 1 (6025 900);
DOT 1 (6025 950);
DOT 1 (6025 750);
DOT 1 (6025 550);
DOT 1 (6025 600);
DOT 1 (6025 650);
DOT 1 (6025 700);
DOT 1 (6025 500);
DOT 1 (6025 350);
DOT 1 (6025 300);
DOT 1 (6025 400);
DOT 1 (6025 450);
DOT 1 (6025 150);
DOT 1 (6025 100);
DOT 1 (6025 50);
DOT 1 (6025 250);
DOT 1 (6025 200);
DOT 1 (3125 3600);
DOT 1 (3125 3550);
DOT 1 (3125 3500);
DOT 1 (3125 3450);
DOT 1 (3125 3400);
DOT 1 (3125 3350);
DOT 1 (3125 3300);
DOT 1 (3125 3250);
DOT 1 (3125 3200);
DOT 1 (3125 3100);
DOT 1 (3125 3150);
DOT 1 (3125 3050);
DOT 1 (3125 3000);
DOT 1 (3125 2950);
DOT 1 (3125 2900);
DOT 1 (3125 2850);
DOT 1 (3125 2800);
DOT 1 (3125 2750);
DOT 1 (3125 2700);
DOT 1 (3125 2650);
DOT 1 (3125 2600);
DOT 1 (3125 2550);
DOT 1 (3125 2500);
DOT 1 (3125 2450);
DOT 1 (3125 2400);
DOT 1 (3125 2350);
DOT 1 (3125 2300);
DOT 1 (3125 2250);
DOT 1 (3125 2200);
DOT 1 (3125 2150);
DOT 1 (3125 2100);
DOT 1 (3000 3600);
DOT 1 (3000 3550);
DOT 1 (3000 3500);
DOT 1 (3000 3450);
DOT 1 (3000 3400);
DOT 1 (3000 3350);
DOT 1 (3000 3300);
DOT 1 (3000 3250);
DOT 1 (3000 3200);
DOT 1 (3000 3150);
DOT 1 (3000 3100);
DOT 1 (3000 3050);
DOT 1 (3000 3000);
DOT 1 (3000 2950);
DOT 1 (3000 2900);
DOT 1 (3000 2850);
DOT 1 (3000 2800);
DOT 1 (3000 2750);
DOT 1 (3000 2700);
DOT 1 (3000 2600);
DOT 1 (3000 2650);
DOT 1 (3000 2500);
DOT 1 (3000 2550);
DOT 1 (3000 2450);
DOT 1 (3000 2400);
DOT 1 (3000 2350);
DOT 1 (3000 2300);
DOT 1 (3000 2250);
DOT 1 (3000 2200);
DOT 1 (3000 2150);
DOT 1 (3000 2100);
DOT 1 (3125 2050);
DOT 1 (3000 2050);
DOT 1 (3125 2000);
DOT 1 (3125 1950);
DOT 1 (3125 1900);
DOT 1 (3125 1850);
DOT 1 (3125 1800);
DOT 1 (3125 1750);
DOT 1 (3125 1700);
DOT 1 (3125 1650);
DOT 1 (3125 1600);
DOT 1 (3125 1550);
DOT 1 (3125 1500);
DOT 1 (3125 1450);
DOT 1 (3125 1300);
DOT 1 (3125 1350);
DOT 1 (3125 1400);
DOT 1 (3125 1200);
DOT 1 (3125 1250);
DOT 1 (3125 1050);
DOT 1 (3125 1100);
DOT 1 (3125 1150);
DOT 1 (3125 1000);
DOT 1 (3125 950);
DOT 1 (3125 900);
DOT 1 (3125 850);
DOT 1 (3125 800);
DOT 1 (3125 700);
DOT 1 (3125 750);
DOT 1 (3125 650);
DOT 1 (3125 600);
DOT 1 (3125 550);
DOT 1 (3125 450);
DOT 1 (3125 400);
DOT 1 (3125 500);
DOT 1 (3125 350);
DOT 1 (3125 300);
DOT 1 (3125 250);
DOT 1 (3125 200);
DOT 1 (3125 150);
DOT 1 (3125 50);
DOT 1 (3125 100);
DOT 1 (3000 2000);
DOT 1 (3000 1950);
DOT 1 (3000 1900);
DOT 1 (3000 1850);
DOT 1 (3000 1800);
DOT 1 (3000 1750);
DOT 1 (3000 1700);
DOT 1 (3000 1650);
DOT 1 (3000 1600);
DOT 1 (3000 1550);
DOT 1 (3000 1500);
DOT 1 (3000 1450);
DOT 1 (3000 1400);
DOT 1 (3000 1350);
DOT 1 (3000 1300);
DOT 1 (3000 1250);
DOT 1 (3000 1200);
DOT 1 (3000 1150);
DOT 1 (3000 1100);
DOT 1 (3000 1050);
DOT 1 (3000 950);
DOT 1 (3000 1000);
DOT 1 (3000 900);
DOT 1 (3000 850);
DOT 1 (3000 800);
DOT 1 (3000 750);
DOT 1 (3000 700);
DOT 1 (3000 650);
DOT 1 (3000 550);
DOT 1 (3000 600);
DOT 1 (3000 450);
DOT 1 (3000 500);
DOT 1 (3000 400);
DOT 1 (3000 350);
DOT 1 (3000 300);
DOT 1 (3000 250);
DOT 1 (3000 200);
DOT 1 (3000 150);
DOT 1 (3000 50);
DOT 1 (3000 100);
DOT 1 (100 3600);
DOT 1 (100 3550);
DOT 1 (100 3500);
DOT 1 (100 3450);
DOT 1 (100 3400);
DOT 1 (100 3350);
DOT 1 (100 3300);
DOT 1 (100 3250);
DOT 1 (100 3150);
DOT 1 (100 3200);
DOT 1 (100 3050);
DOT 1 (100 3000);
DOT 1 (100 2950);
DOT 1 (100 2850);
DOT 1 (100 2900);
DOT 1 (100 2800);
DOT 1 (100 2750);
DOT 1 (100 2700);
DOT 1 (100 2600);
DOT 1 (100 2650);
DOT 1 (100 2550);
DOT 1 (100 2500);
DOT 1 (100 2450);
DOT 1 (100 2350);
DOT 1 (100 2400);
DOT 1 (100 2300);
DOT 1 (100 2250);
DOT 1 (100 2200);
DOT 1 (100 2150);
DOT 1 (100 2100);
DOT 1 (100 2050);
DOT 1 (100 2000);
DOT 1 (100 1950);
DOT 1 (100 1900);
DOT 1 (100 1850);
DOT 1 (100 1800);
DOT 1 (100 1750);
DOT 1 (100 1700);
DOT 1 (100 1650);
DOT 1 (100 1550);
DOT 1 (100 1600);
DOT 1 (100 1450);
DOT 1 (100 1500);
DOT 1 (100 1400);
DOT 1 (100 1350);
DOT 1 (100 1300);
DOT 1 (100 1250);
DOT 1 (100 1200);
DOT 1 (100 1150);
DOT 1 (100 1100);
DOT 1 (100 1050);
DOT 1 (100 1000);
DOT 1 (100 950);
DOT 1 (100 900);
DOT 1 (100 800);
DOT 1 (100 850);
DOT 1 (100 750);
DOT 1 (100 700);
DOT 1 (100 650);
DOT 1 (100 550);
DOT 1 (100 600);
DOT 1 (100 500);
DOT 1 (100 450);
DOT 1 (100 400);
DOT 1 (100 300);
DOT 1 (100 350);
DOT 1 (100 250);
DOT 1 (100 200);
DOT 1 (100 150);
DOT 1 (100 50);
DOT 1 (100 100);
DOT 1 (6025 0);
DOT 1 (6025 -50);
DOT 1 (6025 -200);
DOT 1 (6025 -150);
DOT 1 (6025 -100);
DOT 1 (6025 -250);
DOT 1 (6025 -300);
DOT 1 (3125 0);
DOT 1 (3125 -50);
DOT 1 (3125 -100);
DOT 1 (3125 -200);
DOT 1 (3125 -150);
DOT 1 (3125 -250);
DOT 1 (3125 -300);
DOT 1 (3000 -50);
DOT 1 (3000 0);
DOT 1 (3000 -100);
DOT 1 (3000 -150);
DOT 1 (3000 -200);
DOT 1 (3000 -250);
DOT 1 (3000 -300);
DOT 1 (100 0);
DOT 1 (100 -50);
DOT 1 (100 -100);
DOT 1 (100 -150);
DOT 1 (100 -200);
DOT 1 (100 -250);
DOT 1 (100 -300);
DOT 1 (-50 3600);
DOT 1 (-50 3550);
DOT 1 (-50 3500);
DOT 1 (-50 3450);
DOT 1 (-50 3400);
DOT 1 (-50 3350);
DOT 1 (-50 3300);
DOT 1 (-50 3250);
DOT 1 (-50 3150);
DOT 1 (-50 3100);
DOT 1 (-50 3200);
DOT 1 (-50 3050);
DOT 1 (-50 3000);
DOT 1 (-50 2900);
DOT 1 (-50 2850);
DOT 1 (-50 2800);
DOT 1 (-50 2750);
DOT 1 (-50 2700);
DOT 1 (-50 2600);
DOT 1 (-50 2650);
DOT 1 (-50 2550);
DOT 1 (-50 2500);
DOT 1 (-50 2450);
DOT 1 (-50 2400);
DOT 1 (-50 2350);
DOT 1 (-50 2300);
DOT 1 (-50 2250);
DOT 1 (-50 2200);
DOT 1 (-50 2150);
DOT 1 (-50 2100);
DOT 1 (-50 2050);
DOT 1 (-50 2000);
DOT 1 (-50 1950);
DOT 1 (-50 1900);
DOT 1 (-50 1850);
DOT 1 (-50 1800);
DOT 1 (-50 1750);
DOT 1 (-50 1700);
DOT 1 (-50 1650);
DOT 1 (-50 1600);
DOT 1 (-50 1550);
DOT 1 (-50 1500);
DOT 1 (-50 1450);
DOT 1 (-50 1400);
DOT 1 (-50 1350);
DOT 1 (-50 1300);
DOT 1 (-50 1250);
DOT 1 (-50 1200);
DOT 1 (-50 1150);
DOT 1 (-50 1100);
DOT 1 (-50 1050);
DOT 1 (-50 950);
DOT 1 (-50 800);
DOT 1 (-50 850);
DOT 1 (-50 750);
DOT 1 (-50 700);
DOT 1 (-50 650);
DOT 1 (-50 600);
DOT 1 (-50 550);
DOT 1 (-50 500);
DOT 1 (-50 450);
DOT 1 (-50 400);
DOT 1 (-50 300);
DOT 1 (-50 350);
DOT 1 (-50 250);
DOT 1 (-50 200);
DOT 1 (-50 150);
DOT 1 (-50 50);
DOT 1 (-50 100);
DOT 1 (-2950 3600);
DOT 1 (-2950 3500);
DOT 1 (-2950 3550);
DOT 1 (-2950 3350);
DOT 1 (-2950 3400);
DOT 1 (-2950 3450);
DOT 1 (-2950 3250);
DOT 1 (-2950 3300);
DOT 1 (-2950 3200);
DOT 1 (-2950 3100);
DOT 1 (-2950 3150);
DOT 1 (-2950 3050);
DOT 1 (-2950 3000);
DOT 1 (-2950 2950);
DOT 1 (-2950 2900);
DOT 1 (-2950 2850);
DOT 1 (-2950 2800);
DOT 1 (-2950 2750);
DOT 1 (-2950 2700);
DOT 1 (-2950 2650);
DOT 1 (-2950 2600);
DOT 1 (-2950 2550);
DOT 1 (-2950 2500);
DOT 1 (-2950 2450);
DOT 1 (-2950 2400);
DOT 1 (-2950 2350);
DOT 1 (-2950 2300);
DOT 1 (-2950 2250);
DOT 1 (-2950 2200);
DOT 1 (-2950 2150);
DOT 1 (-2950 2100);
DOT 1 (-2950 2050);
DOT 1 (-2950 1950);
DOT 1 (-2950 2000);
DOT 1 (-2950 1850);
DOT 1 (-2950 1900);
DOT 1 (-2950 1800);
DOT 1 (-2950 1750);
DOT 1 (-2950 1700);
DOT 1 (-2950 1450);
DOT 1 (-2950 1500);
DOT 1 (-2950 1400);
DOT 1 (-2950 1350);
DOT 1 (-2950 1300);
DOT 1 (-2950 1250);
DOT 1 (-2950 1200);
DOT 1 (-2950 1100);
DOT 1 (-2950 1050);
DOT 1 (-2950 1150);
DOT 1 (-2950 1000);
DOT 1 (-2950 950);
DOT 1 (-2950 900);
DOT 1 (-2950 850);
DOT 1 (-2950 800);
DOT 1 (-2950 700);
DOT 1 (-2950 750);
DOT 1 (-2950 650);
DOT 1 (-2950 600);
DOT 1 (-2950 550);
DOT 1 (-2950 450);
DOT 1 (-2950 400);
DOT 1 (-2950 500);
DOT 1 (-2950 350);
DOT 1 (-2950 300);
DOT 1 (-2950 250);
DOT 1 (-2950 200);
DOT 1 (-2950 150);
DOT 1 (-2950 50);
DOT 1 (-2950 100);
DOT 1 (-50 0);
DOT 1 (-50 -50);
DOT 1 (-50 -100);
DOT 1 (-50 -150);
DOT 1 (-50 -200);
DOT 1 (-50 -250);
DOT 1 (-50 -300);
DOT 1 (-2950 0);
DOT 1 (-2950 -100);
DOT 1 (-2950 -50);
DOT 1 (-2950 -150);
DOT 1 (-2950 -200);
DOT 1 (-2950 -300);
DOT 1 (-2950 1650);
DOT 1 (-2950 1600);
DOT 1 (-2950 1550);
DOT 1 (-2950 -250);
DOT 1 (-50 900);
DOT 1 (-50 1000);
QUIT
